FILE_TYPE = MACRO_DRAWING;
SET COLOR_WIRE YELLOW;
SET COLOR_PROP ORANGE;
SET COLOR_DOT WHITE;
SET COLOR_ARC YELLOW;
SET COLOR_BODY GREEN;
SET COLOR_NOTE PURPLE;
SET PROP_DISPLAY VALUE;
SET PAGE_NUMBER P226;
FORCEADD Q_RES..2
(-7700 3575);
FORCEPROP 1 LAST PART_NUMBER CS21002FB06
J 0
(-7660 3400);
DISPLAY 0.510638 (-7660 3400);
DISPLAY INVISIBLE (-7660 3400);
FORCEPROP 1 LAST VALUE 1K
J 0
(-7655 3650);
DISPLAY 0.510638 (-7655 3650);
FORCEPROP 1 LAST TOLERANCE 1%
J 0
(-7655 3600);
DISPLAY 0.510638 (-7655 3600);
FORCEPROP 1 LAST WATTAGE 1/16W
J 0
(-7660 3550);
DISPLAY 0.510638 (-7660 3550);
FORCEPROP 1 LAST PACK_TYPE 0402LF
J 0
(-7660 3450);
DISPLAY 0.510638 (-7660 3450);
FORCEPROP 1 LAST MATERIAL CHIP
J 0
(-7660 3500);
DISPLAY 0.510638 (-7660 3500);
FORCEPROP 1 LAST $LOCATION R1383
J 0
(-7655 3700);
DISPLAY 0.978723 (-7655 3700);
FORCEPROP 1 LASTPIN (-7700 3675) $PN 1
J 0
(-7695 3637);
DISPLAY 0.787234 (-7695 3637);
FORCEPROP 1 LASTPIN (-7700 3475) $PN 2
J 0
(-7695 3485);
DISPLAY 0.787234 (-7695 3485);
FORCEPROP 1 LAST PATH I1
J 0
(-7650 3750);
DISPLAY 0.978723 (-7650 3750);
PAINT WHITE (-7650 3750);
DISPLAY INVISIBLE (-7650 3750);
FORCEPROP 2 LAST CDS_LIB pure_quanta
J 0
(-7700 3575);
PAINT MONO (-7700 3575);
DISPLAY INVISIBLE (-7700 3575);
FORCEPROP 2 LAST CDS_LOCATION R1383
J 0
(-7650 3800);
DISPLAY 1.021277 (-7650 3800);
DISPLAY INVISIBLE (-7650 3800);
FORCEPROP 2 LAST $SEC 1
J 0
(-7650 3800);
DISPLAY 0.680851 (-7650 3800);
PAINT MONO (-7650 3800);
DISPLAY INVISIBLE (-7650 3800);
FORCEPROP 2 LAST CDS_SEC 1
J 0
(-7650 3800);
DISPLAY 1.021277 (-7650 3800);
DISPLAY INVISIBLE (-7650 3800);
FORCEADD Q_RES..1
(-9400 3400);
FORCEPROP 1 LAST PART_NUMBER CS21002FB06
J 0
(-9575 3475);
DISPLAY 0.510638 (-9575 3475);
DISPLAY INVISIBLE (-9575 3475);
FORCEPROP 1 LAST WATTAGE 1/16W
J 2
(-9450 3525);
DISPLAY 0.510638 (-9450 3525);
FORCEPROP 1 LAST VALUE 1K
J 2
(-9225 3400);
DISPLAY 0.510638 (-9225 3400);
FORCEPROP 1 LAST TOLERANCE 1%
J 0
(-9200 3400);
DISPLAY 0.510638 (-9200 3400);
FORCEPROP 1 LAST MATERIAL CHIP
J 0
(-9125 3400);
DISPLAY 0.510638 (-9125 3400);
FORCEPROP 1 LAST PACK_TYPE 0402LF
J 0
(-9425 3525);
DISPLAY 0.510638 (-9425 3525);
FORCEPROP 1 LAST $LOCATION R1347
J 0
(-9625 3400);
DISPLAY 0.638298 (-9625 3400);
FORCEPROP 1 LASTPIN (-9500 3400) $PN 1
J 0
(-9488 3412);
DISPLAY 0.787234 (-9488 3412);
FORCEPROP 1 LASTPIN (-9300 3400) $PN 2
J 0
(-9338 3412);
DISPLAY 0.787234 (-9338 3412);
FORCEPROP 2 LAST CDS_LIB pure_quanta
J 0
(-9400 3400);
DISPLAY INVISIBLE (-9400 3400);
FORCEPROP 1 LAST PATH I10
J 0
(-9450 3550);
DISPLAY 0.978723 (-9450 3550);
PAINT WHITE (-9450 3550);
DISPLAY INVISIBLE (-9450 3550);
FORCEPROP 1 LAST $LOCATION R1347
J 0
(-9450 3600);
DISPLAY 1.021277 (-9450 3600);
DISPLAY INVISIBLE (-9450 3600);
FORCEPROP 2 LAST CDS_LOCATION R1347
J 0
(-9450 3600);
DISPLAY 1.021277 (-9450 3600);
DISPLAY INVISIBLE (-9450 3600);
FORCEPROP 2 LAST $SEC 1
J 0
(-9450 3600);
DISPLAY 0.680851 (-9450 3600);
PAINT MONO (-9450 3600);
DISPLAY INVISIBLE (-9450 3600);
FORCEPROP 2 LAST CDS_SEC 1
J 0
(-9450 3600);
DISPLAY 0.680851 (-9450 3600);
DISPLAY INVISIBLE (-9450 3600);
FORCEADD Q_RES..2
(-10100 3750);
FORCEPROP 1 LAST PART_NUMBER CS21002FB06
J 0
(-10060 3625);
DISPLAY 0.319149 (-10060 3625);
DISPLAY INVISIBLE (-10060 3625);
FORCEPROP 1 LAST MATERIAL CHIP
J 0
(-10060 3675);
DISPLAY 0.510638 (-10060 3675);
FORCEPROP 1 LAST PACK_TYPE 0402LF
J 0
(-10060 3575);
DISPLAY 0.510638 (-10060 3575);
FORCEPROP 1 LAST WATTAGE 1/16W
J 0
(-10060 3725);
DISPLAY 0.510638 (-10060 3725);
FORCEPROP 1 LAST VALUE 1K
J 0
(-10055 3825);
DISPLAY 0.510638 (-10055 3825);
FORCEPROP 1 LAST TOLERANCE 1%
J 0
(-10055 3775);
DISPLAY 0.510638 (-10055 3775);
FORCEPROP 1 LAST $LOCATION R3055
J 0
(-10055 3875);
DISPLAY 0.978723 (-10055 3875);
FORCEPROP 1 LASTPIN (-10100 3850) $PN 1
J 0
(-10095 3812);
DISPLAY 0.787234 (-10095 3812);
FORCEPROP 1 LASTPIN (-10100 3650) $PN 2
J 0
(-10095 3660);
DISPLAY 0.787234 (-10095 3660);
FORCEPROP 2 LAST CDS_LIB pure_quanta
J 0
(-10100 3750);
PAINT MONO (-10100 3750);
DISPLAY INVISIBLE (-10100 3750);
FORCEPROP 1 LAST PATH I11
J 0
(-10050 3925);
DISPLAY 0.978723 (-10050 3925);
PAINT WHITE (-10050 3925);
DISPLAY INVISIBLE (-10050 3925);
FORCEPROP 2 LAST CDS_LOCATION R3055
J 0
(-10050 3975);
DISPLAY 1.021277 (-10050 3975);
DISPLAY INVISIBLE (-10050 3975);
FORCEPROP 2 LAST $SEC 1
J 0
(-10050 3975);
DISPLAY 0.680851 (-10050 3975);
PAINT MONO (-10050 3975);
DISPLAY INVISIBLE (-10050 3975);
FORCEPROP 2 LAST CDS_SEC 1
J 0
(-10050 3975);
DISPLAY 1.021277 (-10050 3975);
DISPLAY INVISIBLE (-10050 3975);
FORCEADD Q_RES..1
(-9850 3050);
FORCEPROP 1 LAST PART_NUMBER CS03322FB03
J 0
(-9950 3000);
DISPLAY 0.404255 (-9950 3000);
DISPLAY INVISIBLE (-9950 3000);
FORCEPROP 1 LAST PACK_TYPE 0402LF
J 0
(-9950 2975);
DISPLAY 0.404255 (-9950 2975);
FORCEPROP 1 LAST WATTAGE 1/16W
J 2
(-9725 2975);
DISPLAY 0.404255 (-9725 2975);
FORCEPROP 1 LAST VALUE 33.2
J 2
(-9675 3050);
DISPLAY 0.404255 (-9675 3050);
FORCEPROP 1 LAST TOLERANCE 1%
J 0
(-9650 3050);
DISPLAY 0.404255 (-9650 3050);
FORCEPROP 1 LAST MATERIAL CHIP
J 0
(-9600 3050);
DISPLAY 0.404255 (-9600 3050);
FORCEPROP 1 LAST $LOCATION R3057
J 0
(-10050 3050);
DISPLAY 0.638298 (-10050 3050);
FORCEPROP 1 LASTPIN (-9950 3050) $PN 1
J 0
(-9938 3062);
DISPLAY 0.787234 (-9938 3062);
FORCEPROP 1 LASTPIN (-9750 3050) $PN 2
J 0
(-9788 3062);
DISPLAY 0.787234 (-9788 3062);
FORCEPROP 1 LAST PATH I12
J 0
(-9900 3200);
DISPLAY 0.978723 (-9900 3200);
PAINT WHITE (-9900 3200);
DISPLAY INVISIBLE (-9900 3200);
FORCEPROP 2 LAST CDS_LIB pure_quanta
J 0
(-9850 3050);
PAINT MONO (-9850 3050);
DISPLAY INVISIBLE (-9850 3050);
FORCEPROP 2 LAST CDS_LOCATION R3057
J 0
(-9900 3250);
DISPLAY 1.021277 (-9900 3250);
DISPLAY INVISIBLE (-9900 3250);
FORCEPROP 2 LAST $SEC 1
J 0
(-9900 3250);
DISPLAY 0.680851 (-9900 3250);
PAINT MONO (-9900 3250);
DISPLAY INVISIBLE (-9900 3250);
FORCEPROP 2 LAST CDS_SEC 1
J 0
(-9900 3250);
DISPLAY 1.021277 (-9900 3250);
DISPLAY INVISIBLE (-9900 3250);
FORCEADD Q_RES..1
(-9850 3150);
FORCEPROP 1 LAST PART_NUMBER CS00002JB13
J 0
(-9975 3000);
DISPLAY 0.510638 (-9975 3000);
DISPLAY INVISIBLE (-9975 3000);
FORCEPROP 1 LAST MATERIAL CHIP
J 0
(-9600 3150);
DISPLAY 0.404255 (-9600 3150);
FORCEPROP 1 LAST TOLERANCE 5%
J 0
(-9650 3150);
DISPLAY 0.404255 (-9650 3150);
FORCEPROP 1 LAST VALUE 0
J 2
(-9675 3150);
DISPLAY 0.404255 (-9675 3150);
FORCEPROP 1 LAST $LOCATION R1345
J 0
(-10050 3150);
DISPLAY 0.638298 (-10050 3150);
FORCEPROP 1 LASTPIN (-9950 3150) $PN 1
J 0
(-9938 3162);
DISPLAY 0.787234 (-9938 3162);
FORCEPROP 1 LASTPIN (-9750 3150) $PN 2
J 0
(-9788 3162);
DISPLAY 0.787234 (-9788 3162);
FORCEPROP 2 LAST CDS_LIB pure_quanta
J 0
(-9850 3150);
PAINT MONO (-9850 3150);
DISPLAY INVISIBLE (-9850 3150);
FORCEPROP 1 LAST PATH I13
J 0
(-9900 3300);
DISPLAY 0.978723 (-9900 3300);
PAINT WHITE (-9900 3300);
DISPLAY INVISIBLE (-9900 3300);
FORCEPROP 1 LAST PACK_TYPE 0402LF
J 0
(-9600 3150);
DISPLAY 0.638298 (-9600 3150);
DISPLAY INVISIBLE (-9600 3150);
FORCEPROP 1 LAST WATTAGE 1/16W
J 2
(-9875 3000);
DISPLAY 0.978723 (-9875 3000);
DISPLAY INVISIBLE (-9875 3000);
FORCEPROP 1 LAST $LOCATION R1345
J 0
(-9900 3350);
DISPLAY 1.021277 (-9900 3350);
DISPLAY INVISIBLE (-9900 3350);
FORCEPROP 2 LAST CDS_LOCATION R1345
J 0
(-9900 3350);
DISPLAY 1.021277 (-9900 3350);
DISPLAY INVISIBLE (-9900 3350);
FORCEPROP 2 LAST $SEC 1
J 0
(-9900 3350);
DISPLAY 0.680851 (-9900 3350);
PAINT MONO (-9900 3350);
DISPLAY INVISIBLE (-9900 3350);
FORCEPROP 2 LAST CDS_SEC 1
J 0
(-9900 3350);
DISPLAY 1.021277 (-9900 3350);
DISPLAY INVISIBLE (-9900 3350);
FORCEADD Q_RES..1
(-9850 3200);
FORCEPROP 1 LAST PART_NUMBER CS00002JB13
J 0
(-9950 3275);
DISPLAY 0.404255 (-9950 3275);
DISPLAY INVISIBLE (-9950 3275);
FORCEPROP 1 LAST VALUE 0
J 2
(-9675 3200);
DISPLAY 0.404255 (-9675 3200);
FORCEPROP 1 LAST MATERIAL CHIP
J 0
(-9600 3200);
DISPLAY 0.404255 (-9600 3200);
FORCEPROP 1 LAST TOLERANCE 5%
J 0
(-9650 3200);
DISPLAY 0.404255 (-9650 3200);
FORCEPROP 1 LAST $LOCATION R1184
J 0
(-10050 3200);
DISPLAY 0.638298 (-10050 3200);
FORCEPROP 1 LASTPIN (-9950 3200) $PN 1
J 0
(-9938 3212);
DISPLAY 0.787234 (-9938 3212);
FORCEPROP 1 LASTPIN (-9750 3200) $PN 2
J 0
(-9788 3212);
DISPLAY 0.787234 (-9788 3212);
FORCEPROP 1 LAST WATTAGE 1/16W
J 2
(-9725 3300);
DISPLAY 0.404255 (-9725 3300);
DISPLAY INVISIBLE (-9725 3300);
FORCEPROP 1 LAST PACK_TYPE 0402LF
J 0
(-9950 3300);
DISPLAY 0.404255 (-9950 3300);
DISPLAY INVISIBLE (-9950 3300);
FORCEPROP 2 LAST CDS_LIB pure_quanta
J 0
(-9850 3200);
PAINT MONO (-9850 3200);
DISPLAY INVISIBLE (-9850 3200);
FORCEPROP 1 LAST PATH I14
J 0
(-9900 3350);
DISPLAY 0.978723 (-9900 3350);
PAINT WHITE (-9900 3350);
DISPLAY INVISIBLE (-9900 3350);
FORCEPROP 1 LAST $LOCATION R1184
J 0
(-9900 3400);
DISPLAY 1.021277 (-9900 3400);
DISPLAY INVISIBLE (-9900 3400);
FORCEPROP 2 LAST CDS_LOCATION R1184
J 0
(-9900 3400);
DISPLAY 1.021277 (-9900 3400);
DISPLAY INVISIBLE (-9900 3400);
FORCEPROP 2 LAST $SEC 1
J 0
(-9900 3400);
DISPLAY 0.680851 (-9900 3400);
PAINT MONO (-9900 3400);
DISPLAY INVISIBLE (-9900 3400);
FORCEPROP 2 LAST CDS_SEC 1
J 0
(-9900 3400);
DISPLAY 1.021277 (-9900 3400);
DISPLAY INVISIBLE (-9900 3400);
FORCEADD UNIVERSAL_POWER..1
(-10825 4025);
FORCEPROP 3 LASTPIN (-10825 3975) SIG_NAME P3V3_AUX\g
J 0
(-10815 3985);
DISPLAY 0.659574 (-10815 3985);
PAINT MONO (-10815 3985);
DISPLAY INVISIBLE (-10815 3985);
FORCEPROP 1 LAST HDL_POWER P3V3_AUX
J 1
(-10825 4075);
DISPLAY 0.872340 (-10825 4075);
PAINT GREEN (-10825 4075);
FORCEPROP 1 LAST PATH I15
J 0
(-10775 4050);
DISPLAY 0.872340 (-10775 4050);
PAINT AQUA (-10775 4050);
DISPLAY INVISIBLE (-10775 4050);
FORCEPROP 2 LAST CDS_LIB logical_power
J 0
(-10825 4025);
PAINT RED (-10825 4025);
DISPLAY INVISIBLE (-10825 4025);
FORCEADD Q_CAP..1
(-10675 3775);
FORCEPROP 1 LAST PART_NUMBER CH5104KEB02
J 0
(-10625 3625);
DISPLAY 0.319149 (-10625 3625);
DISPLAY INVISIBLE (-10625 3625);
FORCEPROP 1 LAST VALUE 1UF
J 0
(-10625 3825);
DISPLAY 0.510638 (-10625 3825);
FORCEPROP 1 LAST VOLTAGE 25V
J 0
(-10625 3775);
DISPLAY 0.510638 (-10625 3775);
FORCEPROP 1 LAST MATERIAL X6S
J 0
(-10625 3675);
DISPLAY 0.510638 (-10625 3675);
FORCEPROP 1 LAST TOLERANCE 10%
J 0
(-10625 3725);
DISPLAY 0.510638 (-10625 3725);
FORCEPROP 1 LAST PACK_TYPE C0402
J 0
(-10625 3575);
DISPLAY 0.510638 (-10625 3575);
FORCEPROP 1 LAST $LOCATION C1291
J 0
(-10625 3875);
DISPLAY 0.978723 (-10625 3875);
FORCEPROP 1 LASTPIN (-10675 3875) $PN 1
J 0
(-10665 3855);
DISPLAY 0.787234 (-10665 3855);
FORCEPROP 1 LASTPIN (-10675 3675) $PN 2
J 0
(-10665 3655);
DISPLAY 0.787234 (-10665 3655);
FORCEPROP 1 LAST PATH I16
J 0
(-10625 3925);
DISPLAY 0.978723 (-10625 3925);
PAINT WHITE (-10625 3925);
DISPLAY INVISIBLE (-10625 3925);
FORCEPROP 2 LAST CDS_LIB pure_quanta
J 0
(-10675 3775);
DISPLAY INVISIBLE (-10675 3775);
FORCEPROP 1 LAST $LOCATION C1291
J 0
(-10625 3975);
DISPLAY 1.021277 (-10625 3975);
DISPLAY INVISIBLE (-10625 3975);
FORCEPROP 2 LAST CDS_LOCATION C1291
J 0
(-10625 3975);
DISPLAY 1.021277 (-10625 3975);
DISPLAY INVISIBLE (-10625 3975);
FORCEPROP 2 LAST $SEC 1
J 0
(-10625 3975);
DISPLAY 0.680851 (-10625 3975);
PAINT MONO (-10625 3975);
DISPLAY INVISIBLE (-10625 3975);
FORCEPROP 2 LAST CDS_SEC 1
J 0
(-10625 3975);
DISPLAY 0.680851 (-10625 3975);
DISPLAY INVISIBLE (-10625 3975);
FORCEADD UNIVERSAL_GND..1
(-10675 3550);
FORCEPROP 3 LASTPIN (-10675 3600) SIG_NAME GND\g
J 0
(-10665 3610);
DISPLAY 0.659574 (-10665 3610);
PAINT MONO (-10665 3610);
DISPLAY INVISIBLE (-10665 3610);
FORCEPROP 1 LAST PATH I17
J 0
(-10600 3550);
DISPLAY 0.872340 (-10600 3550);
PAINT AQUA (-10600 3550);
DISPLAY INVISIBLE (-10600 3550);
FORCEPROP 2 LAST CDS_LIB logical_power
J 0
(-10675 3550);
DISPLAY INVISIBLE (-10675 3550);
FORCEPROP 1 LAST HDL_POWER GND
J 1
(-10650 3475);
DISPLAY 0.872340 (-10650 3475);
PAINT GREEN (-10650 3475);
DISPLAY INVISIBLE (-10650 3475);
FORCEADD GTL2014PW..1
R 2
(-11325 3150);
FORCEPROP 1 LAST PART_NUMBER AL002014K01
J 2
(-11077 3555);
DISPLAY 0.723404 (-11077 3555);
PAINT GREEN (-11077 3555);
DISPLAY INVISIBLE (-11077 3555);
FORCEPROP 2 LAST VALUE GTL2014PW
J 2
(-11100 3650);
DISPLAY 1.021277 (-11100 3650);
FORCEPROP 1 LAST MATERIAL IC
J 2
(-11077 3505);
DISPLAY 0.723404 (-11077 3505);
PAINT GREEN (-11077 3505);
FORCEPROP 2 LAST PART_TYPE SMLF
J 2
(-11100 3700);
DISPLAY 1.021277 (-11100 3700);
FORCEPROP 1 LAST $LOCATION U84
J 2
(-11077 3600);
DISPLAY 0.680851 (-11077 3600);
PAINT GREEN (-11077 3600);
FORCEPROP 2 LASTPIN (-10925 3050) $PN 13
J 0
(-10915 3060);
DISPLAY 0.680851 (-10915 3060);
PAINT MONO (-10915 3060);
FORCEPROP 2 LASTPIN (-10925 3100) $PN 12
J 0
(-10915 3110);
DISPLAY 0.680851 (-10915 3110);
PAINT MONO (-10915 3110);
FORCEPROP 2 LASTPIN (-10925 3150) $PN 10
J 0
(-10915 3160);
DISPLAY 0.680851 (-10915 3160);
PAINT MONO (-10915 3160);
FORCEPROP 2 LASTPIN (-10925 3200) $PN 9
J 0
(-10915 3210);
DISPLAY 0.680851 (-10915 3210);
PAINT MONO (-10915 3210);
FORCEPROP 2 LASTPIN (-11725 3050) $PN 2
J 2
(-11735 3060);
DISPLAY 0.680851 (-11735 3060);
PAINT MONO (-11735 3060);
FORCEPROP 2 LASTPIN (-11725 3100) $PN 3
J 2
(-11735 3110);
DISPLAY 0.680851 (-11735 3110);
PAINT MONO (-11735 3110);
FORCEPROP 2 LASTPIN (-11725 3150) $PN 5
J 2
(-11735 3160);
DISPLAY 0.680851 (-11735 3160);
PAINT MONO (-11735 3160);
FORCEPROP 2 LASTPIN (-11725 3200) $PN 6
J 2
(-11735 3210);
DISPLAY 0.680851 (-11735 3210);
PAINT MONO (-11735 3210);
FORCEPROP 2 LASTPIN (-10925 3300) $PN 1
J 0
(-10915 3310);
DISPLAY 0.680851 (-10915 3310);
PAINT MONO (-10915 3310);
FORCEPROP 2 LASTPIN (-11725 2850) $PN 7
J 2
(-11735 2860);
DISPLAY 0.680851 (-11735 2860);
PAINT MONO (-11735 2860);
FORCEPROP 2 LASTPIN (-11725 2900) $PN 8
J 2
(-11735 2910);
DISPLAY 0.680851 (-11735 2910);
PAINT MONO (-11735 2910);
FORCEPROP 2 LASTPIN (-11725 2950) $PN 11
J 2
(-11735 2960);
DISPLAY 0.680851 (-11735 2960);
PAINT MONO (-11735 2960);
FORCEPROP 2 LASTPIN (-10925 3450) $PN 14
J 0
(-10915 3460);
DISPLAY 0.680851 (-10915 3460);
PAINT MONO (-10915 3460);
FORCEPROP 2 LASTPIN (-10925 3400) $PN 4
J 0
(-10915 3410);
DISPLAY 0.680851 (-10915 3410);
PAINT MONO (-10915 3410);
FORCEPROP 1 LAST PATH I18
J 2
(-11325 3150);
DISPLAY 0.723404 (-11325 3150);
PAINT GREEN (-11325 3150);
DISPLAY INVISIBLE (-11325 3150);
FORCEPROP 1 LAST NEEDS_NO_SIZE TRUE
J 2
(-11325 3150);
DISPLAY 0.723404 (-11325 3150);
PAINT GREEN (-11325 3150);
DISPLAY INVISIBLE (-11325 3150);
FORCEPROP 1 LAST CDS_LMAN_SYM_OUTLINE -250,350,250,-350
J 2
(-11325 3150);
DISPLAY 0.468085 (-11325 3150);
PAINT GREEN (-11325 3150);
DISPLAY INVISIBLE (-11325 3150);
FORCEPROP 2 LAST CDS_LIB pure_quanta
J 2
(-11325 3150);
PAINT RED (-11325 3150);
DISPLAY INVISIBLE (-11325 3150);
FORCEPROP 2 LAST SEC_TYPE 
J 2
(-11100 3750);
DISPLAY 1.021277 (-11100 3750);
DISPLAY INVISIBLE (-11100 3750);
FORCEPROP 1 LAST $LOCATION U84
J 0
(-11100 3750);
DISPLAY 1.021277 (-11100 3750);
DISPLAY INVISIBLE (-11100 3750);
FORCEPROP 2 LAST CDS_LOCATION U84
J 0
(-11100 3750);
DISPLAY 1.021277 (-11100 3750);
DISPLAY INVISIBLE (-11100 3750);
FORCEPROP 2 LAST SEC 1
J 2
(-11100 3750);
DISPLAY 0.680851 (-11100 3750);
PAINT MONO (-11100 3750);
DISPLAY INVISIBLE (-11100 3750);
FORCEADD UNIVERSAL_GND..1
(-11850 2750);
FORCEPROP 3 LASTPIN (-11850 2800) SIG_NAME GND\g
J 0
(-11840 2810);
DISPLAY 0.659574 (-11840 2810);
PAINT MONO (-11840 2810);
DISPLAY INVISIBLE (-11840 2810);
FORCEPROP 1 LAST PATH I19
J 0
(-11775 2750);
DISPLAY 0.872340 (-11775 2750);
PAINT AQUA (-11775 2750);
DISPLAY INVISIBLE (-11775 2750);
FORCEPROP 1 LAST HDL_POWER GND
J 1
(-11825 2675);
DISPLAY 0.872340 (-11825 2675);
PAINT GREEN (-11825 2675);
DISPLAY INVISIBLE (-11825 2675);
FORCEPROP 2 LAST CDS_LIB logical_power
J 0
(-11850 2750);
DISPLAY INVISIBLE (-11850 2750);
FORCEADD OFFPAGE..4
(-7550 3200);
FORCEPROP 2 LAST $XR0 239 
J 0
(-7364 3200);
DISPLAY 0.638298 (-7364 3200);
PAINT MONO (-7364 3200);
FORCEPROP 2 LAST CDS_LIB standard
J 0
(-7550 3200);
PAINT MONO (-7550 3200);
DISPLAY INVISIBLE (-7550 3200);
FORCEPROP 1 LAST OFFPAGE TRUE
J 0
(-7225 3075);
DISPLAY 1.170213 (-7225 3075);
PAINT GREEN (-7225 3075);
DISPLAY INVISIBLE (-7225 3075);
FORCEPROP 1 LAST COMMENT_BODY TRUE
J 0
(-7575 3100);
DISPLAY 1.170213 (-7575 3100);
PAINT GREEN (-7575 3100);
DISPLAY INVISIBLE (-7575 3100);
FORCEPROP 2 LAST PATH I2
J 0
(-7350 3250);
DISPLAY 1.021277 (-7350 3250);
DISPLAY INVISIBLE (-7350 3250);
FORCEADD Q_RES..2
(-8100 2000);
FORCEPROP 1 LAST PART_NUMBER CS21002FB06
J 0
(-8060 1825);
DISPLAY 0.510638 (-8060 1825);
DISPLAY INVISIBLE (-8060 1825);
FORCEPROP 1 LAST VALUE 1K
J 0
(-8055 2075);
DISPLAY 0.510638 (-8055 2075);
FORCEPROP 1 LAST TOLERANCE 1%
J 0
(-8055 2025);
DISPLAY 0.510638 (-8055 2025);
FORCEPROP 1 LAST WATTAGE 1/16W
J 0
(-8060 1975);
DISPLAY 0.510638 (-8060 1975);
FORCEPROP 1 LAST MATERIAL CHIP
J 0
(-8060 1925);
DISPLAY 0.510638 (-8060 1925);
FORCEPROP 1 LAST PACK_TYPE 0402LF
J 0
(-8060 1875);
DISPLAY 0.510638 (-8060 1875);
FORCEPROP 1 LAST $LOCATION R1382
J 0
(-8055 2125);
DISPLAY 0.978723 (-8055 2125);
FORCEPROP 1 LASTPIN (-8100 2100) $PN 1
J 0
(-8095 2062);
DISPLAY 0.787234 (-8095 2062);
FORCEPROP 1 LASTPIN (-8100 1900) $PN 2
J 0
(-8095 1910);
DISPLAY 0.787234 (-8095 1910);
FORCEPROP 2 LAST CDS_LIB pure_quanta
J 0
(-8100 2000);
PAINT MONO (-8100 2000);
DISPLAY INVISIBLE (-8100 2000);
FORCEPROP 1 LAST PATH I20
J 0
(-8050 2175);
DISPLAY 0.978723 (-8050 2175);
PAINT WHITE (-8050 2175);
DISPLAY INVISIBLE (-8050 2175);
FORCEPROP 2 LAST CDS_LOCATION R1382
J 0
(-8050 2225);
DISPLAY 1.021277 (-8050 2225);
DISPLAY INVISIBLE (-8050 2225);
FORCEPROP 2 LAST $SEC 1
J 0
(-8050 2225);
DISPLAY 0.680851 (-8050 2225);
PAINT MONO (-8050 2225);
DISPLAY INVISIBLE (-8050 2225);
FORCEPROP 2 LAST CDS_SEC 1
J 0
(-8050 2225);
DISPLAY 1.021277 (-8050 2225);
DISPLAY INVISIBLE (-8050 2225);
FORCEADD OFFPAGE..2
(-7750 1625);
FORCEPROP 2 LAST $XR0 239 
J 0
(-7561 1625);
DISPLAY 0.638298 (-7561 1625);
PAINT MONO (-7561 1625);
FORCEPROP 1 LAST COMMENT_BODY TRUE
J 0
(-7795 1530);
DISPLAY 0.872340 (-7795 1530);
PAINT GREEN (-7795 1530);
DISPLAY INVISIBLE (-7795 1530);
FORCEPROP 1 LAST OFFPAGE TRUE
J 0
(-7425 1500);
DISPLAY 0.872340 (-7425 1500);
PAINT GREEN (-7425 1500);
DISPLAY INVISIBLE (-7425 1500);
FORCEPROP 2 LAST CDS_LIB standard
J 0
(-7750 1625);
PAINT MONO (-7750 1625);
DISPLAY INVISIBLE (-7750 1625);
FORCEPROP 2 LAST PATH I21
J 0
(-7550 1675);
DISPLAY 1.021277 (-7550 1675);
DISPLAY INVISIBLE (-7550 1675);
FORCEADD OFFPAGE..2
(-7750 1525);
FORCEPROP 2 LAST $XR0 240 
J 0
(-7561 1525);
DISPLAY 0.638298 (-7561 1525);
PAINT MONO (-7561 1525);
FORCEPROP 2 LAST CDS_LIB standard
J 0
(-7750 1525);
PAINT MONO (-7750 1525);
DISPLAY INVISIBLE (-7750 1525);
FORCEPROP 2 LAST PATH I22
J 0
(-7575 1600);
DISPLAY 1.021277 (-7575 1600);
DISPLAY INVISIBLE (-7575 1600);
FORCEPROP 1 LAST COMMENT_BODY TRUE
J 0
(-7795 1430);
DISPLAY 0.872340 (-7795 1430);
PAINT GREEN (-7795 1430);
DISPLAY INVISIBLE (-7795 1430);
FORCEPROP 1 LAST OFFPAGE TRUE
J 0
(-7425 1400);
DISPLAY 0.872340 (-7425 1400);
PAINT GREEN (-7425 1400);
DISPLAY INVISIBLE (-7425 1400);
FORCEADD OFFPAGE..2
(-7100 -300);
FORCEPROP 2 LAST $XR0 221 
J 0
(-6911 -300);
DISPLAY 0.638298 (-6911 -300);
PAINT MONO (-6911 -300);
FORCEPROP 1 LAST OFFPAGE TRUE
J 0
(-6775 -425);
DISPLAY 0.872340 (-6775 -425);
PAINT GREEN (-6775 -425);
DISPLAY INVISIBLE (-6775 -425);
FORCEPROP 1 LAST COMMENT_BODY TRUE
J 0
(-7145 -395);
DISPLAY 0.872340 (-7145 -395);
PAINT GREEN (-7145 -395);
DISPLAY INVISIBLE (-7145 -395);
FORCEPROP 2 LAST CDS_LIB standard
J 0
(-7100 -300);
PAINT MONO (-7100 -300);
DISPLAY INVISIBLE (-7100 -300);
FORCEPROP 2 LAST PATH I26
J 0
(-6900 -250);
DISPLAY 1.021277 (-6900 -250);
DISPLAY INVISIBLE (-6900 -250);
FORCEADD Q_CAP..1
(-7675 300);
FORCEPROP 1 LAST PART_NUMBER CH4104K1B00
J 0
(-7625 150);
DISPLAY 0.510638 (-7625 150);
DISPLAY INVISIBLE (-7625 150);
FORCEPROP 1 LAST PACK_TYPE 0402
J 0
(-7625 100);
DISPLAY 0.510638 (-7625 100);
FORCEPROP 1 LAST TOLERANCE 10%
J 0
(-7625 250);
DISPLAY 0.510638 (-7625 250);
FORCEPROP 1 LAST MATERIAL X7R
J 0
(-7625 200);
DISPLAY 0.510638 (-7625 200);
FORCEPROP 1 LAST VOLTAGE 25V
J 0
(-7625 300);
DISPLAY 0.510638 (-7625 300);
FORCEPROP 1 LAST VALUE 0.1UF
J 0
(-7625 350);
DISPLAY 0.510638 (-7625 350);
FORCEPROP 1 LAST $LOCATION C1322
J 0
(-7625 400);
DISPLAY 0.978723 (-7625 400);
FORCEPROP 1 LASTPIN (-7675 400) $PN 1
J 0
(-7665 380);
DISPLAY 0.787234 (-7665 380);
FORCEPROP 1 LASTPIN (-7675 200) $PN 2
J 0
(-7665 180);
DISPLAY 0.787234 (-7665 180);
FORCEPROP 1 LAST PATH I27
J 0
(-7625 450);
DISPLAY 0.978723 (-7625 450);
PAINT WHITE (-7625 450);
DISPLAY INVISIBLE (-7625 450);
FORCEPROP 2 LAST CDS_LIB pure_quanta
J 0
(-7675 300);
PAINT MONO (-7675 300);
DISPLAY INVISIBLE (-7675 300);
FORCEPROP 2 LAST CDS_LOCATION C1322
J 0
(-7625 500);
DISPLAY 1.021277 (-7625 500);
DISPLAY INVISIBLE (-7625 500);
FORCEPROP 2 LAST $SEC 1
J 0
(-7625 500);
DISPLAY 0.680851 (-7625 500);
PAINT MONO (-7625 500);
DISPLAY INVISIBLE (-7625 500);
FORCEPROP 2 LAST CDS_SEC 1
J 0
(-7625 500);
DISPLAY 1.021277 (-7625 500);
DISPLAY INVISIBLE (-7625 500);
FORCEADD UNIVERSAL_POWER..1
(-7825 575);
FORCEPROP 3 LASTPIN (-7825 525) SIG_NAME P3V3_AUX\g
J 0
(-7815 535);
DISPLAY 0.659574 (-7815 535);
PAINT MONO (-7815 535);
DISPLAY INVISIBLE (-7815 535);
FORCEPROP 1 LAST HDL_POWER P3V3_AUX
J 1
(-7825 625);
DISPLAY 0.872340 (-7825 625);
PAINT GREEN (-7825 625);
FORCEPROP 1 LAST PATH I28
J 0
(-7775 600);
DISPLAY 0.872340 (-7775 600);
PAINT AQUA (-7775 600);
DISPLAY INVISIBLE (-7775 600);
FORCEPROP 2 LAST CDS_LIB logical_power
J 0
(-7825 575);
PAINT MONO (-7825 575);
DISPLAY INVISIBLE (-7825 575);
FORCEADD UNIVERSAL_GND..1
(-7675 100);
FORCEPROP 3 LASTPIN (-7675 150) SIG_NAME GND\g
J 0
(-7665 160);
DISPLAY 0.659574 (-7665 160);
PAINT MONO (-7665 160);
DISPLAY INVISIBLE (-7665 160);
FORCEPROP 1 LAST PATH I29
J 0
(-7600 100);
DISPLAY 0.872340 (-7600 100);
PAINT AQUA (-7600 100);
DISPLAY INVISIBLE (-7600 100);
FORCEPROP 1 LAST HDL_POWER GND
J 1
(-7650 25);
DISPLAY 0.872340 (-7650 25);
PAINT GREEN (-7650 25);
DISPLAY INVISIBLE (-7650 25);
FORCEPROP 2 LAST CDS_LIB logical_power
J 0
(-7675 100);
PAINT MONO (-7675 100);
DISPLAY INVISIBLE (-7675 100);
FORCEADD OFFPAGE..4
(-7550 3150);
FORCEPROP 2 LAST $XR0 239 
J 0
(-7364 3150);
DISPLAY 0.638298 (-7364 3150);
PAINT MONO (-7364 3150);
FORCEPROP 2 LAST CDS_LIB standard
J 0
(-7550 3150);
PAINT MONO (-7550 3150);
DISPLAY INVISIBLE (-7550 3150);
FORCEPROP 1 LAST OFFPAGE TRUE
J 0
(-7225 3025);
DISPLAY 1.170213 (-7225 3025);
PAINT GREEN (-7225 3025);
DISPLAY INVISIBLE (-7225 3025);
FORCEPROP 1 LAST COMMENT_BODY TRUE
J 0
(-7575 3050);
DISPLAY 1.170213 (-7575 3050);
PAINT GREEN (-7575 3050);
DISPLAY INVISIBLE (-7575 3050);
FORCEPROP 2 LAST PATH I3
J 0
(-7350 3200);
DISPLAY 1.021277 (-7350 3200);
DISPLAY INVISIBLE (-7350 3200);
FORCEADD UNIVERSAL_POWER..1
(-8325 2400);
FORCEPROP 3 LASTPIN (-8325 2350) SIG_NAME P3V3_AUX\g
J 0
(-8315 2360);
DISPLAY 0.659574 (-8315 2360);
PAINT MONO (-8315 2360);
DISPLAY INVISIBLE (-8315 2360);
FORCEPROP 1 LAST HDL_POWER P3V3_AUX
J 1
(-8325 2450);
DISPLAY 0.872340 (-8325 2450);
PAINT GREEN (-8325 2450);
FORCEPROP 2 LAST CDS_LIB logical_power
J 0
(-8325 2400);
PAINT MONO (-8325 2400);
DISPLAY INVISIBLE (-8325 2400);
FORCEPROP 1 LAST PATH I30
J 0
(-8275 2425);
DISPLAY 0.872340 (-8275 2425);
PAINT AQUA (-8275 2425);
DISPLAY INVISIBLE (-8275 2425);
FORCEADD Q_RES..2
(-8325 2000);
FORCEPROP 1 LAST PART_NUMBER CS21002FB06
J 0
(-8285 1825);
DISPLAY 0.510638 (-8285 1825);
DISPLAY INVISIBLE (-8285 1825);
FORCEPROP 1 LAST WATTAGE 1/16W
J 0
(-8285 1975);
DISPLAY 0.510638 (-8285 1975);
FORCEPROP 1 LAST TOLERANCE 1%
J 0
(-8280 2025);
DISPLAY 0.510638 (-8280 2025);
FORCEPROP 1 LAST VALUE 1K
J 0
(-8280 2075);
DISPLAY 0.510638 (-8280 2075);
FORCEPROP 1 LAST MATERIAL CHIP
J 0
(-8285 1925);
DISPLAY 0.510638 (-8285 1925);
FORCEPROP 1 LAST PACK_TYPE 0402LF
J 0
(-8285 1875);
DISPLAY 0.510638 (-8285 1875);
FORCEPROP 1 LAST $LOCATION R1380
J 0
(-8280 2125);
DISPLAY 0.978723 (-8280 2125);
FORCEPROP 1 LASTPIN (-8325 2100) $PN 1
J 0
(-8320 2062);
DISPLAY 0.787234 (-8320 2062);
FORCEPROP 1 LASTPIN (-8325 1900) $PN 2
J 0
(-8320 1910);
DISPLAY 0.787234 (-8320 1910);
FORCEPROP 2 LAST CDS_LIB pure_quanta
J 0
(-8325 2000);
PAINT MONO (-8325 2000);
DISPLAY INVISIBLE (-8325 2000);
FORCEPROP 1 LAST PATH I31
J 0
(-8275 2175);
DISPLAY 0.978723 (-8275 2175);
PAINT WHITE (-8275 2175);
DISPLAY INVISIBLE (-8275 2175);
FORCEPROP 2 LAST CDS_LOCATION R1380
J 0
(-8275 2225);
DISPLAY 1.021277 (-8275 2225);
DISPLAY INVISIBLE (-8275 2225);
FORCEPROP 2 LAST $SEC 1
J 0
(-8275 2225);
DISPLAY 0.680851 (-8275 2225);
PAINT MONO (-8275 2225);
DISPLAY INVISIBLE (-8275 2225);
FORCEPROP 2 LAST CDS_SEC 1
J 0
(-8275 2225);
DISPLAY 1.021277 (-8275 2225);
DISPLAY INVISIBLE (-8275 2225);
FORCEADD UNIVERSAL_GND..1
R 2
(-9000 1650);
FORCEPROP 3 LASTPIN (-9000 1700) SIG_NAME GND\g
J 0
(-8990 1710);
DISPLAY 0.659574 (-8990 1710);
PAINT MONO (-8990 1710);
DISPLAY INVISIBLE (-8990 1710);
FORCEPROP 1 LAST HDL_POWER GND
J 1
(-9025 1575);
DISPLAY 0.872340 (-9025 1575);
PAINT GREEN (-9025 1575);
DISPLAY INVISIBLE (-9025 1575);
FORCEPROP 2 LAST CDS_LIB logical_power
R 3
J 0
(-9000 1650);
PAINT MONO (-9000 1650);
DISPLAY INVISIBLE (-9000 1650);
FORCEPROP 1 LAST PATH I32
J 2
(-9075 1650);
DISPLAY 0.872340 (-9075 1650);
PAINT AQUA (-9075 1650);
DISPLAY INVISIBLE (-9075 1650);
FORCEADD Q_RES..1
(-9450 1825);
FORCEPROP 1 LAST PART_NUMBER CS11002FB07
J 0
(-9625 1900);
DISPLAY 0.510638 (-9625 1900);
DISPLAY INVISIBLE (-9625 1900);
FORCEPROP 1 LAST WATTAGE 1/16W
J 2
(-9300 1950);
DISPLAY 0.510638 (-9300 1950);
FORCEPROP 1 LAST MATERIAL CHIP
J 0
(-9150 1825);
DISPLAY 0.510638 (-9150 1825);
FORCEPROP 1 LAST TOLERANCE 1%
J 0
(-9225 1825);
DISPLAY 0.510638 (-9225 1825);
FORCEPROP 1 LAST VALUE 100
J 2
(-9250 1825);
DISPLAY 0.510638 (-9250 1825);
FORCEPROP 1 LAST PACK_TYPE 0402LF
J 0
(-9625 1950);
DISPLAY 0.510638 (-9625 1950);
FORCEPROP 1 LAST $LOCATION R1346
J 0
(-9700 1825);
DISPLAY 0.638298 (-9700 1825);
FORCEPROP 1 LASTPIN (-9550 1825) $PN 1
J 0
(-9538 1837);
DISPLAY 0.787234 (-9538 1837);
PAINT MONO (-9538 1837);
FORCEPROP 1 LASTPIN (-9350 1825) $PN 2
J 0
(-9388 1837);
DISPLAY 0.787234 (-9388 1837);
PAINT MONO (-9388 1837);
FORCEPROP 2 LAST CDS_LIB pure_quanta
J 0
(-9450 1825);
DISPLAY INVISIBLE (-9450 1825);
FORCEPROP 1 LAST PATH I34
J 0
(-9500 1975);
DISPLAY 0.978723 (-9500 1975);
PAINT WHITE (-9500 1975);
DISPLAY INVISIBLE (-9500 1975);
FORCEPROP 2 LAST CDS_LOCATION R1346
J 0
(-9500 2025);
DISPLAY 1.021277 (-9500 2025);
DISPLAY INVISIBLE (-9500 2025);
FORCEPROP 0 LAST $SEC 1
J 0
(-9300 1975);
DISPLAY 0.680851 (-9300 1975);
PAINT MONO (-9300 1975);
DISPLAY INVISIBLE (-9300 1975);
FORCEPROP 2 LAST CDS_SEC 1
J 0
(-9500 2025);
DISPLAY 0.680851 (-9500 2025);
DISPLAY INVISIBLE (-9500 2025);
FORCEADD Q_RES..1
(-9950 1525);
FORCEPROP 1 LAST PART_NUMBER CS03322FB03
J 0
(-10050 1475);
DISPLAY 0.404255 (-10050 1475);
DISPLAY INVISIBLE (-10050 1475);
FORCEPROP 1 LAST TOLERANCE 1%
J 0
(-9700 1525);
DISPLAY 0.638298 (-9700 1525);
FORCEPROP 1 LAST VALUE 33.2
J 2
(-9725 1525);
DISPLAY 0.638298 (-9725 1525);
FORCEPROP 1 LAST MATERIAL CHIP
J 0
(-9625 1525);
DISPLAY 0.638298 (-9625 1525);
FORCEPROP 1 LAST WATTAGE 1/16W
J 2
(-9825 1450);
DISPLAY 0.404255 (-9825 1450);
FORCEPROP 1 LAST PACK_TYPE 0402LF
J 0
(-10050 1450);
DISPLAY 0.404255 (-10050 1450);
FORCEPROP 1 LAST $LOCATION R3056
J 0
(-10150 1525);
DISPLAY 0.638298 (-10150 1525);
FORCEPROP 1 LASTPIN (-10050 1525) $PN 1
J 0
(-10038 1537);
DISPLAY 0.787234 (-10038 1537);
FORCEPROP 1 LASTPIN (-9850 1525) $PN 2
J 0
(-9888 1537);
DISPLAY 0.787234 (-9888 1537);
FORCEPROP 1 LAST PATH I36
J 0
(-10000 1675);
DISPLAY 0.978723 (-10000 1675);
PAINT WHITE (-10000 1675);
DISPLAY INVISIBLE (-10000 1675);
FORCEPROP 2 LAST CDS_LIB pure_quanta
J 0
(-9950 1525);
PAINT MONO (-9950 1525);
DISPLAY INVISIBLE (-9950 1525);
FORCEPROP 2 LAST CDS_LOCATION R3056
J 0
(-10000 1725);
DISPLAY 1.021277 (-10000 1725);
DISPLAY INVISIBLE (-10000 1725);
FORCEPROP 2 LAST $SEC 1
J 0
(-10000 1725);
DISPLAY 0.680851 (-10000 1725);
PAINT MONO (-10000 1725);
DISPLAY INVISIBLE (-10000 1725);
FORCEPROP 2 LAST CDS_SEC 1
J 0
(-10000 1725);
DISPLAY 1.021277 (-10000 1725);
DISPLAY INVISIBLE (-10000 1725);
FORCEADD Q_RES..1
(-9950 1625);
FORCEPROP 1 LAST PART_NUMBER CS00002JB13
J 0
(-10050 1700);
DISPLAY 0.404255 (-10050 1700);
DISPLAY INVISIBLE (-10050 1700);
FORCEPROP 1 LAST TOLERANCE 5%
J 0
(-9775 1625);
DISPLAY 0.638298 (-9775 1625);
FORCEPROP 1 LAST MATERIAL CHIP
J 0
(-9700 1625);
DISPLAY 0.638298 (-9700 1625);
FORCEPROP 1 LAST VALUE 0
J 2
(-9800 1625);
DISPLAY 0.638298 (-9800 1625);
FORCEPROP 1 LAST $LOCATION R483
J 0
(-10150 1625);
DISPLAY 0.638298 (-10150 1625);
FORCEPROP 1 LASTPIN (-10050 1625) $PN 1
J 0
(-10038 1637);
DISPLAY 0.787234 (-10038 1637);
FORCEPROP 1 LASTPIN (-9850 1625) $PN 2
J 0
(-9888 1637);
DISPLAY 0.787234 (-9888 1637);
FORCEPROP 1 LAST WATTAGE 1/16W
J 2
(-9825 1725);
DISPLAY 0.404255 (-9825 1725);
DISPLAY INVISIBLE (-9825 1725);
FORCEPROP 1 LAST PACK_TYPE 0402LF
J 0
(-10050 1725);
DISPLAY 0.404255 (-10050 1725);
DISPLAY INVISIBLE (-10050 1725);
FORCEPROP 1 LAST PATH I37
J 0
(-10000 1775);
DISPLAY 0.978723 (-10000 1775);
PAINT WHITE (-10000 1775);
DISPLAY INVISIBLE (-10000 1775);
FORCEPROP 2 LAST CDS_LIB pure_quanta
J 0
(-9950 1625);
PAINT MONO (-9950 1625);
DISPLAY INVISIBLE (-9950 1625);
FORCEPROP 1 LAST $LOCATION R483
J 0
(-10000 1825);
DISPLAY 1.021277 (-10000 1825);
DISPLAY INVISIBLE (-10000 1825);
FORCEPROP 2 LAST CDS_LOCATION R483
J 0
(-10000 1825);
DISPLAY 1.021277 (-10000 1825);
DISPLAY INVISIBLE (-10000 1825);
FORCEPROP 2 LAST $SEC 1
J 0
(-10000 1825);
DISPLAY 0.680851 (-10000 1825);
PAINT MONO (-10000 1825);
DISPLAY INVISIBLE (-10000 1825);
FORCEPROP 2 LAST CDS_SEC 1
J 0
(-10000 1825);
DISPLAY 1.021277 (-10000 1825);
DISPLAY INVISIBLE (-10000 1825);
FORCEADD NX3L2267GM..1
(-8425 -200);
FORCEPROP 1 LAST PART_NUMBER AL002267000
J 0
(-8670 334);
DISPLAY 0.723404 (-8670 334);
PAINT GREEN (-8670 334);
DISPLAY INVISIBLE (-8670 334);
FORCEPROP 2 LAST PART_TYPE SMLF
J 0
(-8650 400);
DISPLAY 1.021277 (-8650 400);
FORCEPROP 2 LAST VALUE NX3L2267GM
J 0
(-8650 275);
DISPLAY 1.021277 (-8650 275);
FORCEPROP 1 LAST MATERIAL IC
J 0
(-8670 207);
DISPLAY 0.723404 (-8670 207);
PAINT GREEN (-8670 207);
FORCEPROP 1 LAST $LOCATION U97
J 0
(-8675 475);
DISPLAY 0.723404 (-8675 475);
PAINT GREEN (-8675 475);
FORCEPROP 2 LASTPIN (-8825 -300) $PN 8
J 2
(-8835 -290);
DISPLAY 0.680851 (-8835 -290);
PAINT MONO (-8835 -290);
FORCEPROP 2 LASTPIN (-8025 -300) $PN 1
J 0
(-8015 -290);
DISPLAY 0.680851 (-8015 -290);
PAINT MONO (-8015 -290);
FORCEPROP 2 LASTPIN (-8025 0) $PN 2
J 0
(-8015 10);
DISPLAY 0.680851 (-8015 10);
PAINT MONO (-8015 10);
FORCEPROP 2 LASTPIN (-8825 0) $PN 9
J 2
(-8835 10);
DISPLAY 0.680851 (-8835 10);
PAINT MONO (-8835 10);
FORCEPROP 2 LASTPIN (-8825 -400) $PN 7
J 2
(-8835 -390);
DISPLAY 0.680851 (-8835 -390);
PAINT MONO (-8835 -390);
FORCEPROP 2 LASTPIN (-8025 -400) $PN 3
J 0
(-8015 -390);
DISPLAY 0.680851 (-8015 -390);
PAINT MONO (-8015 -390);
FORCEPROP 2 LASTPIN (-8025 -100) $PN 4
J 0
(-8015 -90);
DISPLAY 0.680851 (-8015 -90);
PAINT MONO (-8015 -90);
FORCEPROP 2 LASTPIN (-8825 -100) $PN 6
J 2
(-8835 -90);
DISPLAY 0.680851 (-8835 -90);
PAINT MONO (-8835 -90);
FORCEPROP 2 LASTPIN (-8825 -500) $PN 5
J 2
(-8835 -490);
DISPLAY 0.680851 (-8835 -490);
PAINT MONO (-8835 -490);
FORCEPROP 2 LASTPIN (-8025 100) $PN 10
J 0
(-8015 110);
DISPLAY 0.680851 (-8015 110);
PAINT MONO (-8015 110);
FORCEPROP 2 LAST SEC_TYPE 
J 0
(-8650 525);
DISPLAY 1.021277 (-8650 525);
DISPLAY INVISIBLE (-8650 525);
FORCEPROP 2 LAST CDS_LIB pure_quanta
J 0
(-8425 -200);
DISPLAY INVISIBLE (-8425 -200);
FORCEPROP 1 LAST NEEDS_NO_SIZE TRUE
J 0
(-8425 -200);
DISPLAY 0.723404 (-8425 -200);
PAINT GREEN (-8425 -200);
DISPLAY INVISIBLE (-8425 -200);
FORCEPROP 1 LAST PATH I38
J 0
(-8425 -200);
DISPLAY 0.723404 (-8425 -200);
PAINT GREEN (-8425 -200);
DISPLAY INVISIBLE (-8425 -200);
FORCEPROP 1 LAST CDS_LMAN_SYM_OUTLINE -250,400,250,-400
J 0
(-8425 -200);
DISPLAY 0.468085 (-8425 -200);
PAINT GREEN (-8425 -200);
DISPLAY INVISIBLE (-8425 -200);
FORCEPROP 2 LAST CDS_LOCATION U97
J 0
(-8675 525);
DISPLAY 1.021277 (-8675 525);
DISPLAY INVISIBLE (-8675 525);
FORCEPROP 2 LAST SEC 1
J 0
(-8650 525);
DISPLAY 0.680851 (-8650 525);
PAINT MONO (-8650 525);
DISPLAY INVISIBLE (-8650 525);
FORCEADD UNIVERSAL_GND..1
(-8950 -675);
FORCEPROP 3 LASTPIN (-8950 -625) SIG_NAME GND\g
J 0
(-8940 -615);
DISPLAY 0.659574 (-8940 -615);
PAINT MONO (-8940 -615);
DISPLAY INVISIBLE (-8940 -615);
FORCEPROP 1 LAST PATH I39
J 0
(-8875 -675);
DISPLAY 0.872340 (-8875 -675);
PAINT AQUA (-8875 -675);
DISPLAY INVISIBLE (-8875 -675);
FORCEPROP 1 LAST HDL_POWER GND
J 1
(-8925 -750);
DISPLAY 0.872340 (-8925 -750);
PAINT GREEN (-8925 -750);
DISPLAY INVISIBLE (-8925 -750);
FORCEPROP 2 LAST CDS_LIB logical_power
J 0
(-8950 -675);
PAINT MONO (-8950 -675);
DISPLAY INVISIBLE (-8950 -675);
FORCEADD OFFPAGE..4
(-7550 3100);
FORCEPROP 2 LAST $XR0 214 
J 0
(-7364 3100);
DISPLAY 0.638298 (-7364 3100);
PAINT MONO (-7364 3100);
FORCEPROP 1 LAST COMMENT_BODY TRUE
J 0
(-7575 3000);
DISPLAY 1.170213 (-7575 3000);
PAINT GREEN (-7575 3000);
DISPLAY INVISIBLE (-7575 3000);
FORCEPROP 1 LAST OFFPAGE TRUE
J 0
(-7225 2975);
DISPLAY 1.170213 (-7225 2975);
PAINT GREEN (-7225 2975);
DISPLAY INVISIBLE (-7225 2975);
FORCEPROP 2 LAST CDS_LIB standard
J 0
(-7550 3100);
PAINT MONO (-7550 3100);
DISPLAY INVISIBLE (-7550 3100);
FORCEPROP 2 LAST PATH I4
J 0
(-7350 3150);
DISPLAY 1.021277 (-7350 3150);
DISPLAY INVISIBLE (-7350 3150);
FORCEADD OFFPAGE..1
(-10200 0);
FORCEPROP 2 LAST $XR0 248 
J 0
(-10452 0);
DISPLAY 0.638298 (-10452 0);
PAINT MONO (-10452 0);
FORCEPROP 2 LAST PATH I40
J 0
(-10475 50);
DISPLAY 1.021277 (-10475 50);
DISPLAY INVISIBLE (-10475 50);
FORCEPROP 2 LAST CDS_LIB standard
J 0
(-10200 0);
PAINT MONO (-10200 0);
DISPLAY INVISIBLE (-10200 0);
FORCEPROP 1 LAST OFFPAGE TRUE
J 0
(-9875 -125);
DISPLAY 0.872340 (-9875 -125);
PAINT GREEN (-9875 -125);
DISPLAY INVISIBLE (-9875 -125);
FORCEPROP 1 LAST COMMENT_BODY TRUE
J 0
(-10075 -100);
DISPLAY 0.872340 (-10075 -100);
PAINT GREEN (-10075 -100);
DISPLAY INVISIBLE (-10075 -100);
FORCEADD OFFPAGE..1
(-10200 -100);
FORCEPROP 2 LAST $XR0 248 
J 0
(-10452 -100);
DISPLAY 0.638298 (-10452 -100);
PAINT MONO (-10452 -100);
FORCEPROP 2 LAST PATH I41
J 0
(-10475 -50);
DISPLAY 1.021277 (-10475 -50);
DISPLAY INVISIBLE (-10475 -50);
FORCEPROP 2 LAST CDS_LIB standard
J 0
(-10200 -100);
PAINT MONO (-10200 -100);
DISPLAY INVISIBLE (-10200 -100);
FORCEPROP 1 LAST COMMENT_BODY TRUE
J 0
(-10075 -200);
DISPLAY 0.872340 (-10075 -200);
PAINT GREEN (-10075 -200);
DISPLAY INVISIBLE (-10075 -200);
FORCEPROP 1 LAST OFFPAGE TRUE
J 0
(-9875 -225);
DISPLAY 0.872340 (-9875 -225);
PAINT GREEN (-9875 -225);
DISPLAY INVISIBLE (-9875 -225);
FORCEADD UNIVERSAL_POWER..1
(-10850 2450);
FORCEPROP 3 LASTPIN (-10850 2400) SIG_NAME P3V3_AUX\g
J 0
(-10840 2410);
DISPLAY 0.659574 (-10840 2410);
PAINT MONO (-10840 2410);
DISPLAY INVISIBLE (-10840 2410);
FORCEPROP 1 LAST HDL_POWER P3V3_AUX
J 1
(-10850 2500);
DISPLAY 0.872340 (-10850 2500);
PAINT GREEN (-10850 2500);
FORCEPROP 1 LAST PATH I42
J 0
(-10800 2475);
DISPLAY 0.872340 (-10800 2475);
PAINT AQUA (-10800 2475);
DISPLAY INVISIBLE (-10800 2475);
FORCEPROP 2 LAST CDS_LIB logical_power
J 0
(-10850 2450);
PAINT RED (-10850 2450);
DISPLAY INVISIBLE (-10850 2450);
FORCEADD Q_CAP..1
(-10700 2200);
FORCEPROP 1 LAST PART_NUMBER CH5104KEB02
J 0
(-10650 2050);
DISPLAY 0.404255 (-10650 2050);
DISPLAY INVISIBLE (-10650 2050);
FORCEPROP 1 LAST MATERIAL X6S
J 0
(-10650 2100);
DISPLAY 0.510638 (-10650 2100);
FORCEPROP 1 LAST VALUE 1UF
J 0
(-10650 2250);
DISPLAY 0.510638 (-10650 2250);
FORCEPROP 1 LAST VOLTAGE 25V
J 0
(-10650 2200);
DISPLAY 0.510638 (-10650 2200);
FORCEPROP 1 LAST TOLERANCE 10%
J 0
(-10650 2150);
DISPLAY 0.510638 (-10650 2150);
FORCEPROP 1 LAST PACK_TYPE C0402
J 0
(-10650 2000);
DISPLAY 0.510638 (-10650 2000);
FORCEPROP 1 LAST $LOCATION C1290
J 0
(-10650 2300);
DISPLAY 0.978723 (-10650 2300);
FORCEPROP 1 LASTPIN (-10700 2300) $PN 1
J 0
(-10690 2280);
DISPLAY 0.787234 (-10690 2280);
FORCEPROP 1 LASTPIN (-10700 2100) $PN 2
J 0
(-10690 2080);
DISPLAY 0.787234 (-10690 2080);
FORCEPROP 1 LAST PATH I43
J 0
(-10650 2350);
DISPLAY 0.978723 (-10650 2350);
PAINT WHITE (-10650 2350);
DISPLAY INVISIBLE (-10650 2350);
FORCEPROP 2 LAST CDS_LIB pure_quanta
J 0
(-10700 2200);
DISPLAY INVISIBLE (-10700 2200);
FORCEPROP 1 LAST $LOCATION C1290
J 0
(-10650 2400);
DISPLAY 1.021277 (-10650 2400);
DISPLAY INVISIBLE (-10650 2400);
FORCEPROP 2 LAST CDS_LOCATION C1290
J 0
(-10650 2400);
DISPLAY 1.021277 (-10650 2400);
DISPLAY INVISIBLE (-10650 2400);
FORCEPROP 2 LAST $SEC 1
J 0
(-10650 2400);
DISPLAY 0.680851 (-10650 2400);
PAINT MONO (-10650 2400);
DISPLAY INVISIBLE (-10650 2400);
FORCEPROP 2 LAST CDS_SEC 1
J 0
(-10650 2400);
DISPLAY 0.680851 (-10650 2400);
DISPLAY INVISIBLE (-10650 2400);
FORCEADD UNIVERSAL_GND..1
(-10700 1975);
FORCEPROP 3 LASTPIN (-10700 2025) SIG_NAME GND\g
J 0
(-10690 2035);
DISPLAY 0.659574 (-10690 2035);
PAINT MONO (-10690 2035);
DISPLAY INVISIBLE (-10690 2035);
FORCEPROP 1 LAST PATH I44
J 0
(-10625 1975);
DISPLAY 0.872340 (-10625 1975);
PAINT AQUA (-10625 1975);
DISPLAY INVISIBLE (-10625 1975);
FORCEPROP 2 LAST CDS_LIB logical_power
J 0
(-10700 1975);
DISPLAY INVISIBLE (-10700 1975);
FORCEPROP 1 LAST HDL_POWER GND
J 1
(-10675 1900);
DISPLAY 0.872340 (-10675 1900);
PAINT GREEN (-10675 1900);
DISPLAY INVISIBLE (-10675 1900);
FORCEADD GTL2014PW..1
R 2
(-11350 1575);
FORCEPROP 1 LAST PART_NUMBER AL002014K01
J 2
(-11102 1980);
DISPLAY 0.723404 (-11102 1980);
PAINT GREEN (-11102 1980);
DISPLAY INVISIBLE (-11102 1980);
FORCEPROP 2 LAST PART_TYPE SMLF
J 2
(-11125 2125);
DISPLAY 1.021277 (-11125 2125);
FORCEPROP 1 LAST MATERIAL IC
J 2
(-11102 1930);
DISPLAY 0.723404 (-11102 1930);
PAINT GREEN (-11102 1930);
FORCEPROP 2 LAST VALUE GTL2014PW
J 2
(-11125 2075);
DISPLAY 1.021277 (-11125 2075);
FORCEPROP 1 LAST $LOCATION U83
J 2
(-11102 2025);
DISPLAY 0.680851 (-11102 2025);
PAINT GREEN (-11102 2025);
FORCEPROP 2 LASTPIN (-10950 1475) $PN 13
J 0
(-10940 1485);
DISPLAY 0.680851 (-10940 1485);
PAINT MONO (-10940 1485);
FORCEPROP 2 LASTPIN (-10950 1525) $PN 12
J 0
(-10940 1535);
DISPLAY 0.680851 (-10940 1535);
PAINT MONO (-10940 1535);
FORCEPROP 2 LASTPIN (-10950 1575) $PN 10
J 0
(-10940 1585);
DISPLAY 0.680851 (-10940 1585);
PAINT MONO (-10940 1585);
FORCEPROP 2 LASTPIN (-10950 1625) $PN 9
J 0
(-10940 1635);
DISPLAY 0.680851 (-10940 1635);
PAINT MONO (-10940 1635);
FORCEPROP 2 LASTPIN (-11750 1475) $PN 2
J 2
(-11760 1485);
DISPLAY 0.680851 (-11760 1485);
PAINT MONO (-11760 1485);
FORCEPROP 2 LASTPIN (-11750 1525) $PN 3
J 2
(-11760 1535);
DISPLAY 0.680851 (-11760 1535);
PAINT MONO (-11760 1535);
FORCEPROP 2 LASTPIN (-11750 1575) $PN 5
J 2
(-11760 1585);
DISPLAY 0.680851 (-11760 1585);
PAINT MONO (-11760 1585);
FORCEPROP 2 LASTPIN (-11750 1625) $PN 6
J 2
(-11760 1635);
DISPLAY 0.680851 (-11760 1635);
PAINT MONO (-11760 1635);
FORCEPROP 2 LASTPIN (-10950 1725) $PN 1
J 0
(-10940 1735);
DISPLAY 0.680851 (-10940 1735);
PAINT MONO (-10940 1735);
FORCEPROP 2 LASTPIN (-11750 1275) $PN 7
J 2
(-11760 1285);
DISPLAY 0.680851 (-11760 1285);
PAINT MONO (-11760 1285);
FORCEPROP 2 LASTPIN (-11750 1325) $PN 8
J 2
(-11760 1335);
DISPLAY 0.680851 (-11760 1335);
PAINT MONO (-11760 1335);
FORCEPROP 2 LASTPIN (-11750 1375) $PN 11
J 2
(-11760 1385);
DISPLAY 0.680851 (-11760 1385);
PAINT MONO (-11760 1385);
FORCEPROP 2 LASTPIN (-10950 1875) $PN 14
J 0
(-10940 1885);
DISPLAY 0.680851 (-10940 1885);
PAINT MONO (-10940 1885);
FORCEPROP 2 LASTPIN (-10950 1825) $PN 4
J 0
(-10940 1835);
DISPLAY 0.680851 (-10940 1835);
PAINT MONO (-10940 1835);
FORCEPROP 1 LAST PATH I45
J 2
(-11350 1575);
DISPLAY 0.723404 (-11350 1575);
PAINT GREEN (-11350 1575);
DISPLAY INVISIBLE (-11350 1575);
FORCEPROP 1 LAST NEEDS_NO_SIZE TRUE
J 2
(-11350 1575);
DISPLAY 0.723404 (-11350 1575);
PAINT GREEN (-11350 1575);
DISPLAY INVISIBLE (-11350 1575);
FORCEPROP 1 LAST CDS_LMAN_SYM_OUTLINE -250,350,250,-350
J 2
(-11350 1575);
DISPLAY 0.468085 (-11350 1575);
PAINT GREEN (-11350 1575);
DISPLAY INVISIBLE (-11350 1575);
FORCEPROP 2 LAST CDS_LIB pure_quanta
J 2
(-11350 1575);
PAINT RED (-11350 1575);
DISPLAY INVISIBLE (-11350 1575);
FORCEPROP 2 LAST SEC_TYPE 
J 2
(-11125 2175);
DISPLAY 1.021277 (-11125 2175);
DISPLAY INVISIBLE (-11125 2175);
FORCEPROP 1 LAST $LOCATION U83
J 0
(-11125 2175);
DISPLAY 1.021277 (-11125 2175);
DISPLAY INVISIBLE (-11125 2175);
FORCEPROP 2 LAST CDS_LOCATION U83
J 0
(-11125 2175);
DISPLAY 1.021277 (-11125 2175);
DISPLAY INVISIBLE (-11125 2175);
FORCEPROP 2 LAST SEC 1
J 2
(-11125 2175);
DISPLAY 0.680851 (-11125 2175);
PAINT MONO (-11125 2175);
DISPLAY INVISIBLE (-11125 2175);
FORCEADD UNIVERSAL_GND..1
(-11875 1175);
FORCEPROP 3 LASTPIN (-11875 1225) SIG_NAME GND\g
J 0
(-11865 1235);
DISPLAY 0.659574 (-11865 1235);
PAINT MONO (-11865 1235);
DISPLAY INVISIBLE (-11865 1235);
FORCEPROP 1 LAST PATH I46
J 0
(-11800 1175);
DISPLAY 0.872340 (-11800 1175);
PAINT AQUA (-11800 1175);
DISPLAY INVISIBLE (-11800 1175);
FORCEPROP 1 LAST HDL_POWER GND
J 1
(-11850 1100);
DISPLAY 0.872340 (-11850 1100);
PAINT GREEN (-11850 1100);
DISPLAY INVISIBLE (-11850 1100);
FORCEPROP 2 LAST CDS_LIB logical_power
J 0
(-11875 1175);
DISPLAY INVISIBLE (-11875 1175);
FORCEADD Q_RES..2
(-12425 1250);
FORCEPROP 1 LAST PART_NUMBER CS21002FB06
J 0
(-12385 1075);
DISPLAY 0.510638 (-12385 1075);
DISPLAY INVISIBLE (-12385 1075);
FORCEPROP 1 LAST TOLERANCE 1%
J 0
(-12380 1275);
DISPLAY 0.510638 (-12380 1275);
FORCEPROP 1 LAST VALUE 1K
J 0
(-12380 1325);
DISPLAY 0.510638 (-12380 1325);
FORCEPROP 1 LAST PACK_TYPE 0402LF
J 0
(-12385 1125);
DISPLAY 0.510638 (-12385 1125);
FORCEPROP 1 LAST MATERIAL CHIP
J 0
(-12385 1175);
DISPLAY 0.510638 (-12385 1175);
FORCEPROP 1 LAST WATTAGE 1/16W
J 0
(-12385 1225);
DISPLAY 0.510638 (-12385 1225);
FORCEPROP 1 LAST $LOCATION R1369
J 0
(-12380 1375);
DISPLAY 0.978723 (-12380 1375);
FORCEPROP 1 LASTPIN (-12425 1350) $PN 1
J 0
(-12420 1312);
DISPLAY 0.787234 (-12420 1312);
FORCEPROP 1 LASTPIN (-12425 1150) $PN 2
J 0
(-12420 1160);
DISPLAY 0.787234 (-12420 1160);
FORCEPROP 1 LAST PATH I47
J 0
(-12375 1425);
DISPLAY 0.978723 (-12375 1425);
PAINT WHITE (-12375 1425);
DISPLAY INVISIBLE (-12375 1425);
FORCEPROP 2 LAST CDS_LIB pure_quanta
J 0
(-12425 1250);
PAINT MONO (-12425 1250);
DISPLAY INVISIBLE (-12425 1250);
FORCEPROP 2 LAST CDS_LOCATION R1369
J 0
(-12375 1475);
DISPLAY 1.021277 (-12375 1475);
DISPLAY INVISIBLE (-12375 1475);
FORCEPROP 2 LAST $SEC 1
J 0
(-12375 1475);
DISPLAY 0.680851 (-12375 1475);
PAINT MONO (-12375 1475);
DISPLAY INVISIBLE (-12375 1475);
FORCEPROP 2 LAST CDS_SEC 1
J 0
(-12375 1475);
DISPLAY 1.021277 (-12375 1475);
DISPLAY INVISIBLE (-12375 1475);
FORCEADD Q_RES..2
(-12650 1250);
FORCEPROP 1 LAST PART_NUMBER CS21002FB06
J 0
(-12610 1075);
DISPLAY 0.510638 (-12610 1075);
DISPLAY INVISIBLE (-12610 1075);
FORCEPROP 1 LAST MATERIAL CHIP
J 0
(-12610 1175);
DISPLAY 0.510638 (-12610 1175);
FORCEPROP 1 LAST TOLERANCE 1%
J 0
(-12605 1275);
DISPLAY 0.510638 (-12605 1275);
FORCEPROP 1 LAST VALUE 1K
J 0
(-12605 1325);
DISPLAY 0.510638 (-12605 1325);
FORCEPROP 1 LAST WATTAGE 1/16W
J 0
(-12610 1225);
DISPLAY 0.510638 (-12610 1225);
FORCEPROP 1 LAST PACK_TYPE 0402LF
J 0
(-12610 1125);
DISPLAY 0.510638 (-12610 1125);
FORCEPROP 1 LAST $LOCATION R1368
J 0
(-12605 1375);
DISPLAY 0.978723 (-12605 1375);
FORCEPROP 1 LASTPIN (-12650 1350) $PN 1
J 0
(-12645 1312);
DISPLAY 0.787234 (-12645 1312);
FORCEPROP 1 LASTPIN (-12650 1150) $PN 2
J 0
(-12645 1160);
DISPLAY 0.787234 (-12645 1160);
FORCEPROP 1 LAST PATH I48
J 0
(-12600 1425);
DISPLAY 0.978723 (-12600 1425);
PAINT WHITE (-12600 1425);
DISPLAY INVISIBLE (-12600 1425);
FORCEPROP 2 LAST CDS_LIB pure_quanta
J 0
(-12650 1250);
PAINT MONO (-12650 1250);
DISPLAY INVISIBLE (-12650 1250);
FORCEPROP 2 LAST CDS_LOCATION R1368
J 0
(-12600 1475);
DISPLAY 1.021277 (-12600 1475);
DISPLAY INVISIBLE (-12600 1475);
FORCEPROP 2 LAST $SEC 1
J 0
(-12600 1475);
DISPLAY 0.680851 (-12600 1475);
PAINT MONO (-12600 1475);
DISPLAY INVISIBLE (-12600 1475);
FORCEPROP 2 LAST CDS_SEC 1
J 0
(-12600 1475);
DISPLAY 1.021277 (-12600 1475);
DISPLAY INVISIBLE (-12600 1475);
FORCEADD UNIVERSAL_GND..1
(-12650 975);
FORCEPROP 3 LASTPIN (-12650 1025) SIG_NAME GND\g
J 0
(-12640 1035);
DISPLAY 0.659574 (-12640 1035);
PAINT MONO (-12640 1035);
DISPLAY INVISIBLE (-12640 1035);
FORCEPROP 1 LAST PATH I49
J 0
(-12575 975);
DISPLAY 0.872340 (-12575 975);
PAINT AQUA (-12575 975);
DISPLAY INVISIBLE (-12575 975);
FORCEPROP 2 LAST CDS_LIB logical_power
J 0
(-12650 975);
PAINT MONO (-12650 975);
DISPLAY INVISIBLE (-12650 975);
FORCEPROP 1 LAST HDL_POWER GND
J 1
(-12625 900);
DISPLAY 0.872340 (-12625 900);
PAINT GREEN (-12625 900);
DISPLAY INVISIBLE (-12625 900);
FORCEADD OFFPAGE..4
(-7550 3050);
FORCEPROP 2 LAST $XR0 240 
J 0
(-7364 3050);
DISPLAY 0.638298 (-7364 3050);
PAINT MONO (-7364 3050);
FORCEPROP 2 LAST CDS_LIB standard
J 0
(-7550 3050);
PAINT MONO (-7550 3050);
DISPLAY INVISIBLE (-7550 3050);
FORCEPROP 2 LAST PATH I5
J 0
(-7375 3125);
DISPLAY 1.021277 (-7375 3125);
DISPLAY INVISIBLE (-7375 3125);
FORCEPROP 1 LAST OFFPAGE TRUE
J 0
(-7225 2925);
DISPLAY 1.170213 (-7225 2925);
PAINT GREEN (-7225 2925);
DISPLAY INVISIBLE (-7225 2925);
FORCEPROP 1 LAST COMMENT_BODY TRUE
J 0
(-7575 2950);
DISPLAY 1.170213 (-7575 2950);
PAINT GREEN (-7575 2950);
DISPLAY INVISIBLE (-7575 2950);
FORCEADD OFFPAGE..4
(-11150 -100);
FORCEPROP 2 LAST $XR0 239 
J 0
(-10964 -100);
DISPLAY 0.638298 (-10964 -100);
PAINT MONO (-10964 -100);
FORCEPROP 2 LAST CDS_LIB standard
J 0
(-11150 -100);
PAINT MONO (-11150 -100);
DISPLAY INVISIBLE (-11150 -100);
FORCEPROP 1 LAST OFFPAGE TRUE
J 0
(-10825 -225);
DISPLAY 0.872340 (-10825 -225);
PAINT GREEN (-10825 -225);
DISPLAY INVISIBLE (-10825 -225);
FORCEPROP 1 LAST COMMENT_BODY TRUE
J 0
(-11175 -200);
DISPLAY 0.872340 (-11175 -200);
PAINT PEACH (-11175 -200);
DISPLAY INVISIBLE (-11175 -200);
FORCEPROP 2 LAST PATH I51
J 0
(-10950 -50);
DISPLAY 1.021277 (-10950 -50);
DISPLAY INVISIBLE (-10950 -50);
FORCEADD OFFPAGE..4
(-11150 -400);
FORCEPROP 2 LAST $XR0 221 
J 0
(-10964 -400);
DISPLAY 0.638298 (-10964 -400);
PAINT MONO (-10964 -400);
FORCEPROP 2 LAST PATH I52
J 0
(-10800 -350);
DISPLAY 1.021277 (-10800 -350);
DISPLAY INVISIBLE (-10800 -350);
FORCEPROP 1 LAST OFFPAGE TRUE
J 0
(-10825 -525);
DISPLAY 0.872340 (-10825 -525);
PAINT GREEN (-10825 -525);
DISPLAY INVISIBLE (-10825 -525);
FORCEPROP 1 LAST COMMENT_BODY TRUE
J 0
(-11175 -500);
DISPLAY 0.872340 (-11175 -500);
PAINT PEACH (-11175 -500);
DISPLAY INVISIBLE (-11175 -500);
FORCEPROP 2 LAST CDS_LIB standard
J 0
(-11150 -400);
PAINT MONO (-11150 -400);
DISPLAY INVISIBLE (-11150 -400);
FORCEADD OFFPAGE..2
(-11150 -300);
FORCEPROP 2 LAST $XR0 221 
J 0
(-10961 -300);
DISPLAY 0.638298 (-10961 -300);
PAINT MONO (-10961 -300);
FORCEPROP 1 LAST OFFPAGE TRUE
J 0
(-10825 -425);
DISPLAY 0.872340 (-10825 -425);
PAINT GREEN (-10825 -425);
DISPLAY INVISIBLE (-10825 -425);
FORCEPROP 1 LAST COMMENT_BODY TRUE
J 0
(-11195 -395);
DISPLAY 0.872340 (-11195 -395);
PAINT GREEN (-11195 -395);
DISPLAY INVISIBLE (-11195 -395);
FORCEPROP 2 LAST CDS_LIB standard
J 0
(-11150 -300);
PAINT MONO (-11150 -300);
DISPLAY INVISIBLE (-11150 -300);
FORCEPROP 2 LAST PATH I53
J 0
(-10800 -250);
DISPLAY 1.021277 (-10800 -250);
DISPLAY INVISIBLE (-10800 -250);
FORCEADD UNIVERSAL_POWER..1
(-11875 575);
FORCEPROP 3 LASTPIN (-11875 525) SIG_NAME P3V3_AUX\g
J 0
(-11865 535);
DISPLAY 0.659574 (-11865 535);
PAINT MONO (-11865 535);
DISPLAY INVISIBLE (-11865 535);
FORCEPROP 1 LAST HDL_POWER P3V3_AUX
J 1
(-11875 625);
DISPLAY 0.872340 (-11875 625);
PAINT GREEN (-11875 625);
FORCEPROP 1 LAST PATH I54
J 0
(-11825 600);
DISPLAY 0.872340 (-11825 600);
PAINT AQUA (-11825 600);
DISPLAY INVISIBLE (-11825 600);
FORCEPROP 2 LAST CDS_LIB logical_power
J 0
(-11875 575);
PAINT MONO (-11875 575);
DISPLAY INVISIBLE (-11875 575);
FORCEADD Q_CAP..1
(-11725 300);
FORCEPROP 1 LAST PART_NUMBER CH4104K1B00
J 0
(-11675 150);
DISPLAY 0.510638 (-11675 150);
DISPLAY INVISIBLE (-11675 150);
FORCEPROP 1 LAST PACK_TYPE 0402
J 0
(-11675 100);
DISPLAY 0.510638 (-11675 100);
FORCEPROP 1 LAST TOLERANCE 10%
J 0
(-11675 250);
DISPLAY 0.510638 (-11675 250);
FORCEPROP 1 LAST VOLTAGE 25V
J 0
(-11675 300);
DISPLAY 0.510638 (-11675 300);
FORCEPROP 1 LAST MATERIAL X7R
J 0
(-11675 200);
DISPLAY 0.510638 (-11675 200);
FORCEPROP 1 LAST VALUE 0.1UF
J 0
(-11675 350);
DISPLAY 0.510638 (-11675 350);
FORCEPROP 1 LAST $LOCATION C1321
J 0
(-11675 400);
DISPLAY 0.787234 (-11675 400);
FORCEPROP 1 LASTPIN (-11725 400) $PN 1
J 0
(-11715 380);
DISPLAY 0.787234 (-11715 380);
FORCEPROP 1 LASTPIN (-11725 200) $PN 2
J 0
(-11715 180);
DISPLAY 0.787234 (-11715 180);
FORCEPROP 1 LAST PATH I55
J 0
(-11675 450);
DISPLAY 0.978723 (-11675 450);
PAINT WHITE (-11675 450);
DISPLAY INVISIBLE (-11675 450);
FORCEPROP 2 LAST CDS_LIB pure_quanta
J 2
(-11725 300);
PAINT MONO (-11725 300);
DISPLAY INVISIBLE (-11725 300);
FORCEPROP 2 LAST CDS_LOCATION C1321
J 0
(-11675 500);
DISPLAY 1.021277 (-11675 500);
DISPLAY INVISIBLE (-11675 500);
FORCEPROP 2 LAST $SEC 1
J 0
(-11675 500);
DISPLAY 0.680851 (-11675 500);
PAINT MONO (-11675 500);
DISPLAY INVISIBLE (-11675 500);
FORCEPROP 2 LAST CDS_SEC 1
J 0
(-11675 500);
DISPLAY 1.021277 (-11675 500);
DISPLAY INVISIBLE (-11675 500);
FORCEADD UNIVERSAL_GND..1
(-11725 100);
FORCEPROP 3 LASTPIN (-11725 150) SIG_NAME GND\g
J 0
(-11715 160);
DISPLAY 0.659574 (-11715 160);
PAINT MONO (-11715 160);
DISPLAY INVISIBLE (-11715 160);
FORCEPROP 1 LAST PATH I56
J 0
(-11650 100);
DISPLAY 0.872340 (-11650 100);
PAINT AQUA (-11650 100);
DISPLAY INVISIBLE (-11650 100);
FORCEPROP 2 LAST CDS_LIB logical_power
J 0
(-11725 100);
PAINT MONO (-11725 100);
DISPLAY INVISIBLE (-11725 100);
FORCEPROP 1 LAST HDL_POWER GND
J 1
(-11700 25);
DISPLAY 0.872340 (-11700 25);
PAINT GREEN (-11700 25);
DISPLAY INVISIBLE (-11700 25);
FORCEADD Q_RES..1
(-13050 3050);
FORCEPROP 1 LAST PART_NUMBER CS00002JB13
J 0
(-13175 2900);
DISPLAY 0.510638 (-13175 2900);
DISPLAY INVISIBLE (-13175 2900);
FORCEPROP 1 LAST MATERIAL CHIP
J 0
(-12800 3050);
DISPLAY 0.638298 (-12800 3050);
FORCEPROP 1 LAST TOLERANCE 5%
J 0
(-12875 3050);
DISPLAY 0.638298 (-12875 3050);
FORCEPROP 1 LAST VALUE 0
J 2
(-12900 3050);
DISPLAY 0.638298 (-12900 3050);
FORCEPROP 1 LAST $LOCATION R482
J 0
(-13250 3050);
DISPLAY 0.638298 (-13250 3050);
FORCEPROP 1 LASTPIN (-13150 3050) $PN 1
J 0
(-13138 3062);
DISPLAY 0.787234 (-13138 3062);
FORCEPROP 1 LASTPIN (-12950 3050) $PN 2
J 0
(-12988 3062);
DISPLAY 0.787234 (-12988 3062);
FORCEPROP 1 LAST PATH I57
J 0
(-13100 3200);
DISPLAY 0.978723 (-13100 3200);
PAINT WHITE (-13100 3200);
DISPLAY INVISIBLE (-13100 3200);
FORCEPROP 1 LAST PACK_TYPE 0402LF
J 0
(-12800 3050);
DISPLAY 0.638298 (-12800 3050);
DISPLAY INVISIBLE (-12800 3050);
FORCEPROP 1 LAST WATTAGE 1/16W
J 2
(-13075 2900);
DISPLAY 0.978723 (-13075 2900);
DISPLAY INVISIBLE (-13075 2900);
FORCEPROP 2 LAST CDS_LIB pure_quanta
J 0
(-13050 3050);
PAINT MONO (-13050 3050);
DISPLAY INVISIBLE (-13050 3050);
FORCEPROP 1 LAST $LOCATION R482
J 0
(-13100 3250);
DISPLAY 1.021277 (-13100 3250);
DISPLAY INVISIBLE (-13100 3250);
FORCEPROP 2 LAST CDS_LOCATION R482
J 0
(-13100 3250);
DISPLAY 1.021277 (-13100 3250);
DISPLAY INVISIBLE (-13100 3250);
FORCEPROP 2 LAST $SEC 1
J 0
(-13100 3250);
DISPLAY 0.680851 (-13100 3250);
PAINT MONO (-13100 3250);
DISPLAY INVISIBLE (-13100 3250);
FORCEPROP 2 LAST CDS_SEC 1
J 0
(-13100 3250);
DISPLAY 1.021277 (-13100 3250);
DISPLAY INVISIBLE (-13100 3250);
FORCEADD Q_RES..1
(-13050 3150);
FORCEPROP 1 LAST PART_NUMBER CS00002JB13
J 0
(-13175 3000);
DISPLAY 0.510638 (-13175 3000);
DISPLAY INVISIBLE (-13175 3000);
FORCEPROP 1 LAST MATERIAL CHIP
J 0
(-12800 3150);
DISPLAY 0.638298 (-12800 3150);
FORCEPROP 1 LAST VALUE 0
J 2
(-12900 3150);
DISPLAY 0.638298 (-12900 3150);
FORCEPROP 1 LAST TOLERANCE 5%
J 0
(-12875 3150);
DISPLAY 0.638298 (-12875 3150);
FORCEPROP 1 LAST $LOCATION R481
J 0
(-13250 3150);
DISPLAY 0.638298 (-13250 3150);
FORCEPROP 1 LASTPIN (-13150 3150) $PN 1
J 0
(-13138 3162);
DISPLAY 0.787234 (-13138 3162);
FORCEPROP 1 LASTPIN (-12950 3150) $PN 2
J 0
(-12988 3162);
DISPLAY 0.787234 (-12988 3162);
FORCEPROP 1 LAST PATH I58
J 0
(-13100 3300);
DISPLAY 0.978723 (-13100 3300);
PAINT WHITE (-13100 3300);
DISPLAY INVISIBLE (-13100 3300);
FORCEPROP 2 LAST CDS_LIB pure_quanta
J 0
(-13050 3150);
PAINT MONO (-13050 3150);
DISPLAY INVISIBLE (-13050 3150);
FORCEPROP 1 LAST WATTAGE 1/16W
J 2
(-13075 3000);
DISPLAY 0.978723 (-13075 3000);
DISPLAY INVISIBLE (-13075 3000);
FORCEPROP 1 LAST PACK_TYPE 0402LF
J 0
(-12800 3150);
DISPLAY 0.638298 (-12800 3150);
DISPLAY INVISIBLE (-12800 3150);
FORCEPROP 1 LAST $LOCATION R481
J 0
(-13100 3350);
DISPLAY 1.021277 (-13100 3350);
DISPLAY INVISIBLE (-13100 3350);
FORCEPROP 2 LAST CDS_LOCATION R481
J 0
(-13100 3350);
DISPLAY 1.021277 (-13100 3350);
DISPLAY INVISIBLE (-13100 3350);
FORCEPROP 2 LAST $SEC 1
J 0
(-13100 3350);
DISPLAY 0.680851 (-13100 3350);
PAINT MONO (-13100 3350);
DISPLAY INVISIBLE (-13100 3350);
FORCEPROP 2 LAST CDS_SEC 1
J 0
(-13100 3350);
DISPLAY 1.021277 (-13100 3350);
DISPLAY INVISIBLE (-13100 3350);
FORCEADD Q_RES..1
(-13050 3200);
FORCEPROP 1 LAST PART_NUMBER CS00002JB13
J 0
(-13150 2975);
DISPLAY 0.404255 (-13150 2975);
DISPLAY INVISIBLE (-13150 2975);
FORCEPROP 1 LAST MATERIAL CHIP
J 0
(-12800 3200);
DISPLAY 0.638298 (-12800 3200);
FORCEPROP 1 LAST PACK_TYPE 0402LF
J 0
(-13150 3000);
DISPLAY 0.404255 (-13150 3000);
FORCEPROP 1 LAST TOLERANCE 5%
J 0
(-12875 3200);
DISPLAY 0.638298 (-12875 3200);
FORCEPROP 1 LAST VALUE 0
J 2
(-12900 3200);
DISPLAY 0.638298 (-12900 3200);
FORCEPROP 1 LAST WATTAGE 1/16W
J 2
(-12925 3000);
DISPLAY 0.404255 (-12925 3000);
FORCEPROP 1 LAST $LOCATION R480
J 0
(-13250 3200);
DISPLAY 0.638298 (-13250 3200);
FORCEPROP 1 LASTPIN (-13150 3200) $PN 1
J 0
(-13138 3212);
DISPLAY 0.787234 (-13138 3212);
FORCEPROP 1 LASTPIN (-12950 3200) $PN 2
J 0
(-12988 3212);
DISPLAY 0.787234 (-12988 3212);
FORCEPROP 1 LAST PATH I59
J 0
(-13100 3350);
DISPLAY 0.978723 (-13100 3350);
PAINT WHITE (-13100 3350);
DISPLAY INVISIBLE (-13100 3350);
FORCEPROP 2 LAST CDS_LIB pure_quanta
J 0
(-13050 3200);
PAINT MONO (-13050 3200);
DISPLAY INVISIBLE (-13050 3200);
FORCEPROP 1 LAST $LOCATION R480
J 0
(-13100 3400);
DISPLAY 1.021277 (-13100 3400);
DISPLAY INVISIBLE (-13100 3400);
FORCEPROP 2 LAST CDS_LOCATION R480
J 0
(-13100 3400);
DISPLAY 1.021277 (-13100 3400);
DISPLAY INVISIBLE (-13100 3400);
FORCEPROP 2 LAST $SEC 1
J 0
(-13100 3400);
DISPLAY 0.680851 (-13100 3400);
PAINT MONO (-13100 3400);
DISPLAY INVISIBLE (-13100 3400);
FORCEPROP 2 LAST CDS_SEC 1
J 0
(-13100 3400);
DISPLAY 1.021277 (-13100 3400);
DISPLAY INVISIBLE (-13100 3400);
FORCEADD UNIVERSAL_POWER..1
(-7925 3975);
FORCEPROP 3 LASTPIN (-7925 3925) SIG_NAME P3V3_AUX\g
J 0
(-7915 3935);
DISPLAY 0.659574 (-7915 3935);
PAINT MONO (-7915 3935);
DISPLAY INVISIBLE (-7915 3935);
FORCEPROP 1 LAST HDL_POWER P3V3_AUX
J 1
(-7925 4025);
DISPLAY 0.872340 (-7925 4025);
PAINT GREEN (-7925 4025);
FORCEPROP 1 LAST PATH I6
J 0
(-7875 4000);
DISPLAY 0.872340 (-7875 4000);
PAINT AQUA (-7875 4000);
DISPLAY INVISIBLE (-7875 4000);
FORCEPROP 2 LAST CDS_LIB logical_power
J 0
(-7925 3975);
PAINT MONO (-7925 3975);
DISPLAY INVISIBLE (-7925 3975);
FORCEADD OFFPAGE..5
(-14075 3200);
FORCEPROP 2 LAST $XR1 132 
J 0
(-14450 3200);
DISPLAY 0.638298 (-14450 3200);
PAINT MONO (-14450 3200);
FORCEPROP 2 LAST $XR0 131 
J 0
(-14330 3200);
DISPLAY 0.638298 (-14330 3200);
PAINT MONO (-14330 3200);
FORCEPROP 2 LAST PATH I60
J 0
(-14350 3250);
DISPLAY 1.021277 (-14350 3250);
DISPLAY INVISIBLE (-14350 3250);
FORCEPROP 2 LAST CDS_LIB standard
J 0
(-14075 3200);
PAINT MONO (-14075 3200);
DISPLAY INVISIBLE (-14075 3200);
FORCEPROP 1 LAST COMMENT_BODY TRUE
J 0
(-13975 3125);
DISPLAY 0.872340 (-13975 3125);
PAINT PEACH (-13975 3125);
DISPLAY INVISIBLE (-13975 3125);
FORCEPROP 1 LAST OFFPAGE TRUE
J 0
(-13750 3075);
DISPLAY 0.872340 (-13750 3075);
PAINT GREEN (-13750 3075);
DISPLAY INVISIBLE (-13750 3075);
FORCEADD OFFPAGE..5
(-14075 3150);
FORCEPROP 2 LAST $XR1 132 
J 0
(-14450 3150);
DISPLAY 0.638298 (-14450 3150);
PAINT MONO (-14450 3150);
FORCEPROP 2 LAST $XR0 131 
J 0
(-14330 3150);
DISPLAY 0.638298 (-14330 3150);
PAINT MONO (-14330 3150);
FORCEPROP 2 LAST PATH I61
J 0
(-14350 3200);
DISPLAY 1.021277 (-14350 3200);
DISPLAY INVISIBLE (-14350 3200);
FORCEPROP 1 LAST COMMENT_BODY TRUE
J 0
(-13975 3075);
DISPLAY 0.872340 (-13975 3075);
PAINT PEACH (-13975 3075);
DISPLAY INVISIBLE (-13975 3075);
FORCEPROP 1 LAST OFFPAGE TRUE
J 0
(-13750 3025);
DISPLAY 0.872340 (-13750 3025);
PAINT GREEN (-13750 3025);
DISPLAY INVISIBLE (-13750 3025);
FORCEPROP 2 LAST CDS_LIB standard
J 0
(-14075 3150);
PAINT MONO (-14075 3150);
DISPLAY INVISIBLE (-14075 3150);
FORCEADD OFFPAGE..5
(-14075 3100);
FORCEPROP 2 LAST $XR1 203 
J 0
(-14450 3100);
DISPLAY 0.638298 (-14450 3100);
PAINT MONO (-14450 3100);
FORCEPROP 2 LAST $XR0 131 
J 0
(-14330 3100);
DISPLAY 0.638298 (-14330 3100);
PAINT MONO (-14330 3100);
FORCEPROP 2 LAST PATH I62
J 0
(-14350 3150);
DISPLAY 1.021277 (-14350 3150);
DISPLAY INVISIBLE (-14350 3150);
FORCEPROP 1 LAST COMMENT_BODY TRUE
J 0
(-13975 3025);
DISPLAY 0.872340 (-13975 3025);
PAINT PEACH (-13975 3025);
DISPLAY INVISIBLE (-13975 3025);
FORCEPROP 1 LAST OFFPAGE TRUE
J 0
(-13750 2975);
DISPLAY 0.872340 (-13750 2975);
PAINT GREEN (-13750 2975);
DISPLAY INVISIBLE (-13750 2975);
FORCEPROP 2 LAST CDS_LIB standard
J 0
(-14075 3100);
PAINT MONO (-14075 3100);
DISPLAY INVISIBLE (-14075 3100);
FORCEADD OFFPAGE..5
(-14075 3050);
FORCEPROP 2 LAST $XR1 132 
J 0
(-14450 3050);
DISPLAY 0.638298 (-14450 3050);
PAINT MONO (-14450 3050);
FORCEPROP 2 LAST $XR0 131 
J 0
(-14330 3050);
DISPLAY 0.638298 (-14330 3050);
PAINT MONO (-14330 3050);
FORCEPROP 2 LAST PATH I63
J 0
(-14350 3100);
DISPLAY 1.021277 (-14350 3100);
DISPLAY INVISIBLE (-14350 3100);
FORCEPROP 1 LAST COMMENT_BODY TRUE
J 0
(-13975 2975);
DISPLAY 0.872340 (-13975 2975);
PAINT PEACH (-13975 2975);
DISPLAY INVISIBLE (-13975 2975);
FORCEPROP 1 LAST OFFPAGE TRUE
J 0
(-13750 2925);
DISPLAY 0.872340 (-13750 2925);
PAINT GREEN (-13750 2925);
DISPLAY INVISIBLE (-13750 2925);
FORCEPROP 2 LAST CDS_LIB standard
J 0
(-14075 3050);
PAINT MONO (-14075 3050);
DISPLAY INVISIBLE (-14075 3050);
FORCEADD Q_RES..1
(-13075 1625);
FORCEPROP 1 LAST PART_NUMBER CS11002FB07
J 0
(-13175 1675);
DISPLAY 0.404255 (-13175 1675);
DISPLAY INVISIBLE (-13175 1675);
FORCEPROP 1 LAST MATERIAL CHIP
J 0
(-12800 1625);
DISPLAY 0.510638 (-12800 1625);
FORCEPROP 1 LAST VALUE 100
J 2
(-12900 1625);
DISPLAY 0.510638 (-12900 1625);
FORCEPROP 1 LAST TOLERANCE 1%
J 0
(-12875 1625);
DISPLAY 0.510638 (-12875 1625);
FORCEPROP 1 LAST WATTAGE 1/16W
J 2
(-12950 1700);
DISPLAY 0.404255 (-12950 1700);
FORCEPROP 1 LAST PACK_TYPE 0402LF
J 0
(-13175 1700);
DISPLAY 0.404255 (-13175 1700);
FORCEPROP 1 LAST $LOCATION R1366
J 0
(-13300 1625);
DISPLAY 0.638298 (-13300 1625);
FORCEPROP 1 LASTPIN (-13175 1625) $PN 1
J 0
(-13163 1637);
DISPLAY 0.787234 (-13163 1637);
FORCEPROP 1 LASTPIN (-12975 1625) $PN 2
J 0
(-13013 1637);
DISPLAY 0.787234 (-13013 1637);
FORCEPROP 1 LAST PATH I64
J 0
(-13125 1775);
DISPLAY 0.978723 (-13125 1775);
PAINT WHITE (-13125 1775);
DISPLAY INVISIBLE (-13125 1775);
FORCEPROP 2 LAST CDS_LIB pure_quanta
J 0
(-13075 1625);
PAINT MONO (-13075 1625);
DISPLAY INVISIBLE (-13075 1625);
FORCEPROP 2 LAST CDS_LOCATION R1366
J 0
(-13125 1825);
DISPLAY 1.021277 (-13125 1825);
DISPLAY INVISIBLE (-13125 1825);
FORCEPROP 2 LAST $SEC 1
J 0
(-13125 1825);
DISPLAY 0.680851 (-13125 1825);
PAINT MONO (-13125 1825);
DISPLAY INVISIBLE (-13125 1825);
FORCEPROP 2 LAST CDS_SEC 1
J 0
(-13125 1825);
DISPLAY 1.021277 (-13125 1825);
DISPLAY INVISIBLE (-13125 1825);
FORCEADD Q_RES..1
(-13075 1525);
FORCEPROP 1 LAST PART_NUMBER CS11002FB07
J 0
(-13175 1575);
DISPLAY 0.404255 (-13175 1575);
DISPLAY INVISIBLE (-13175 1575);
FORCEPROP 1 LAST MATERIAL CHIP
J 0
(-12800 1525);
DISPLAY 0.510638 (-12800 1525);
FORCEPROP 1 LAST TOLERANCE 1%
J 0
(-12875 1525);
DISPLAY 0.510638 (-12875 1525);
FORCEPROP 1 LAST VALUE 100
J 2
(-12900 1525);
DISPLAY 0.510638 (-12900 1525);
FORCEPROP 1 LAST $LOCATION R1367
J 0
(-13300 1525);
DISPLAY 0.638298 (-13300 1525);
FORCEPROP 1 LASTPIN (-13175 1525) $PN 1
J 0
(-13163 1537);
DISPLAY 0.787234 (-13163 1537);
FORCEPROP 1 LASTPIN (-12975 1525) $PN 2
J 0
(-13013 1537);
DISPLAY 0.787234 (-13013 1537);
FORCEPROP 1 LAST PATH I65
J 0
(-13125 1675);
DISPLAY 0.978723 (-13125 1675);
PAINT WHITE (-13125 1675);
DISPLAY INVISIBLE (-13125 1675);
FORCEPROP 1 LAST WATTAGE 1/16W
J 2
(-12950 1600);
DISPLAY 0.404255 (-12950 1600);
DISPLAY INVISIBLE (-12950 1600);
FORCEPROP 1 LAST PACK_TYPE 0402LF
J 0
(-13175 1600);
DISPLAY 0.404255 (-13175 1600);
DISPLAY INVISIBLE (-13175 1600);
FORCEPROP 2 LAST CDS_LIB pure_quanta
J 0
(-13075 1525);
PAINT MONO (-13075 1525);
DISPLAY INVISIBLE (-13075 1525);
FORCEPROP 2 LAST CDS_LOCATION R1367
J 0
(-13125 1725);
DISPLAY 1.021277 (-13125 1725);
DISPLAY INVISIBLE (-13125 1725);
FORCEPROP 2 LAST $SEC 1
J 0
(-13125 1725);
DISPLAY 0.680851 (-13125 1725);
PAINT MONO (-13125 1725);
DISPLAY INVISIBLE (-13125 1725);
FORCEPROP 2 LAST CDS_SEC 1
J 0
(-13125 1725);
DISPLAY 1.021277 (-13125 1725);
DISPLAY INVISIBLE (-13125 1725);
FORCEADD OFFPAGE..1
(-14100 1625);
FORCEPROP 2 LAST $XR1 131 
J 0
(-14502 1625);
DISPLAY 0.638298 (-14502 1625);
PAINT MONO (-14502 1625);
FORCEPROP 2 LAST $XR0 132 
J 0
(-14382 1625);
DISPLAY 0.638298 (-14382 1625);
PAINT MONO (-14382 1625);
FORCEPROP 2 LAST PATH I66
J 0
(-14375 1675);
DISPLAY 1.021277 (-14375 1675);
DISPLAY INVISIBLE (-14375 1675);
FORCEPROP 1 LAST COMMENT_BODY TRUE
J 0
(-13975 1525);
DISPLAY 0.872340 (-13975 1525);
PAINT GREEN (-13975 1525);
DISPLAY INVISIBLE (-13975 1525);
FORCEPROP 1 LAST OFFPAGE TRUE
J 0
(-13775 1500);
DISPLAY 0.872340 (-13775 1500);
PAINT GREEN (-13775 1500);
DISPLAY INVISIBLE (-13775 1500);
FORCEPROP 2 LAST CDS_LIB standard
J 0
(-14100 1625);
PAINT MONO (-14100 1625);
DISPLAY INVISIBLE (-14100 1625);
FORCEADD OFFPAGE..1
(-14100 1525);
FORCEPROP 2 LAST $XR1 132 
J 0
(-14502 1525);
DISPLAY 0.638298 (-14502 1525);
PAINT MONO (-14502 1525);
FORCEPROP 2 LAST $XR0 131 
J 0
(-14382 1525);
DISPLAY 0.638298 (-14382 1525);
PAINT MONO (-14382 1525);
FORCEPROP 2 LAST PATH I67
J 0
(-14400 1575);
DISPLAY 1.021277 (-14400 1575);
DISPLAY INVISIBLE (-14400 1575);
FORCEPROP 1 LAST OFFPAGE TRUE
J 0
(-13775 1400);
DISPLAY 0.872340 (-13775 1400);
PAINT GREEN (-13775 1400);
DISPLAY INVISIBLE (-13775 1400);
FORCEPROP 1 LAST COMMENT_BODY TRUE
J 0
(-13975 1425);
DISPLAY 0.872340 (-13975 1425);
PAINT GREEN (-13975 1425);
DISPLAY INVISIBLE (-13975 1425);
FORCEPROP 2 LAST CDS_LIB standard
J 0
(-14100 1525);
PAINT MONO (-14100 1525);
DISPLAY INVISIBLE (-14100 1525);
FORCEADD NX3L2267GM..1
(-12475 -200);
FORCEPROP 1 LAST PART_NUMBER AL002267000
J 0
(-12720 334);
DISPLAY 0.723404 (-12720 334);
PAINT GREEN (-12720 334);
DISPLAY INVISIBLE (-12720 334);
FORCEPROP 1 LAST MATERIAL IC
J 0
(-12720 207);
DISPLAY 0.723404 (-12720 207);
PAINT GREEN (-12720 207);
FORCEPROP 2 LAST PART_TYPE SMLF
J 0
(-12725 275);
DISPLAY 1.021277 (-12725 275);
FORCEPROP 2 LAST VALUE NX3L2267GM
J 0
(-12725 375);
DISPLAY 1.021277 (-12725 375);
FORCEPROP 1 LAST $LOCATION U96
J 0
(-12725 425);
DISPLAY 0.723404 (-12725 425);
PAINT GREEN (-12725 425);
FORCEPROP 2 LASTPIN (-12875 -300) $PN 8
J 2
(-12885 -290);
DISPLAY 0.680851 (-12885 -290);
PAINT MONO (-12885 -290);
FORCEPROP 2 LASTPIN (-12075 -300) $PN 1
J 0
(-12065 -290);
DISPLAY 0.680851 (-12065 -290);
PAINT MONO (-12065 -290);
FORCEPROP 2 LASTPIN (-12075 0) $PN 2
J 0
(-12065 10);
DISPLAY 0.680851 (-12065 10);
PAINT MONO (-12065 10);
FORCEPROP 2 LASTPIN (-12875 0) $PN 9
J 2
(-12885 10);
DISPLAY 0.680851 (-12885 10);
PAINT MONO (-12885 10);
FORCEPROP 2 LASTPIN (-12875 -400) $PN 7
J 2
(-12885 -390);
DISPLAY 0.680851 (-12885 -390);
PAINT MONO (-12885 -390);
FORCEPROP 2 LASTPIN (-12075 -400) $PN 3
J 0
(-12065 -390);
DISPLAY 0.680851 (-12065 -390);
PAINT MONO (-12065 -390);
FORCEPROP 2 LASTPIN (-12075 -100) $PN 4
J 0
(-12065 -90);
DISPLAY 0.680851 (-12065 -90);
PAINT MONO (-12065 -90);
FORCEPROP 2 LASTPIN (-12875 -100) $PN 6
J 2
(-12885 -90);
DISPLAY 0.680851 (-12885 -90);
PAINT MONO (-12885 -90);
FORCEPROP 2 LASTPIN (-12875 -500) $PN 5
J 2
(-12885 -490);
DISPLAY 0.680851 (-12885 -490);
PAINT MONO (-12885 -490);
FORCEPROP 2 LASTPIN (-12075 100) $PN 10
J 0
(-12065 110);
DISPLAY 0.680851 (-12065 110);
PAINT MONO (-12065 110);
FORCEPROP 2 LAST SEC_TYPE 
J 0
(-12700 525);
DISPLAY 1.021277 (-12700 525);
DISPLAY INVISIBLE (-12700 525);
FORCEPROP 2 LAST CDS_LIB pure_quanta
J 0
(-12475 -200);
DISPLAY INVISIBLE (-12475 -200);
FORCEPROP 1 LAST NEEDS_NO_SIZE TRUE
J 0
(-12475 -200);
DISPLAY 0.723404 (-12475 -200);
PAINT GREEN (-12475 -200);
DISPLAY INVISIBLE (-12475 -200);
FORCEPROP 1 LAST PATH I68
J 0
(-12475 -200);
DISPLAY 0.723404 (-12475 -200);
PAINT GREEN (-12475 -200);
DISPLAY INVISIBLE (-12475 -200);
FORCEPROP 1 LAST CDS_LMAN_SYM_OUTLINE -250,400,250,-400
J 0
(-12475 -200);
DISPLAY 0.468085 (-12475 -200);
PAINT GREEN (-12475 -200);
DISPLAY INVISIBLE (-12475 -200);
FORCEPROP 2 LAST CDS_LOCATION U96
J 0
(-12725 525);
DISPLAY 1.021277 (-12725 525);
DISPLAY INVISIBLE (-12725 525);
FORCEPROP 2 LAST SEC 1
J 0
(-12700 525);
DISPLAY 0.680851 (-12700 525);
PAINT MONO (-12700 525);
DISPLAY INVISIBLE (-12700 525);
FORCEADD UNIVERSAL_GND..1
(-13000 -675);
FORCEPROP 3 LASTPIN (-13000 -625) SIG_NAME GND\g
J 0
(-12990 -615);
DISPLAY 0.659574 (-12990 -615);
PAINT MONO (-12990 -615);
DISPLAY INVISIBLE (-12990 -615);
FORCEPROP 1 LAST PATH I69
J 0
(-12925 -675);
DISPLAY 0.872340 (-12925 -675);
PAINT AQUA (-12925 -675);
DISPLAY INVISIBLE (-12925 -675);
FORCEPROP 2 LAST CDS_LIB logical_power
J 0
(-13000 -675);
PAINT MONO (-13000 -675);
DISPLAY INVISIBLE (-13000 -675);
FORCEPROP 1 LAST HDL_POWER GND
J 1
(-12975 -750);
DISPLAY 0.872340 (-12975 -750);
PAINT GREEN (-12975 -750);
DISPLAY INVISIBLE (-12975 -750);
FORCEADD Q_RES..2
(-7925 3575);
FORCEPROP 1 LAST PART_NUMBER CS21002FB06
J 0
(-7885 3400);
DISPLAY 0.510638 (-7885 3400);
DISPLAY INVISIBLE (-7885 3400);
FORCEPROP 1 LAST PACK_TYPE 0402LF
J 0
(-7885 3450);
DISPLAY 0.510638 (-7885 3450);
FORCEPROP 1 LAST MATERIAL CHIP
J 0
(-7885 3500);
DISPLAY 0.510638 (-7885 3500);
FORCEPROP 1 LAST VALUE 1K
J 0
(-7880 3650);
DISPLAY 0.510638 (-7880 3650);
FORCEPROP 1 LAST TOLERANCE 1%
J 0
(-7880 3600);
DISPLAY 0.510638 (-7880 3600);
FORCEPROP 1 LAST WATTAGE 1/16W
J 0
(-7885 3550);
DISPLAY 0.510638 (-7885 3550);
FORCEPROP 1 LAST $LOCATION R1381
J 0
(-7880 3700);
DISPLAY 0.978723 (-7880 3700);
FORCEPROP 1 LASTPIN (-7925 3675) $PN 1
J 0
(-7920 3637);
DISPLAY 0.787234 (-7920 3637);
FORCEPROP 1 LASTPIN (-7925 3475) $PN 2
J 0
(-7920 3485);
DISPLAY 0.787234 (-7920 3485);
FORCEPROP 1 LAST PATH I7
J 0
(-7875 3750);
DISPLAY 0.978723 (-7875 3750);
PAINT WHITE (-7875 3750);
DISPLAY INVISIBLE (-7875 3750);
FORCEPROP 2 LAST CDS_LIB pure_quanta
J 0
(-7925 3575);
PAINT MONO (-7925 3575);
DISPLAY INVISIBLE (-7925 3575);
FORCEPROP 2 LAST CDS_LOCATION R1381
J 0
(-7875 3800);
DISPLAY 1.021277 (-7875 3800);
DISPLAY INVISIBLE (-7875 3800);
FORCEPROP 2 LAST $SEC 1
J 0
(-7875 3800);
DISPLAY 0.680851 (-7875 3800);
PAINT MONO (-7875 3800);
DISPLAY INVISIBLE (-7875 3800);
FORCEPROP 2 LAST CDS_SEC 1
J 0
(-7875 3800);
DISPLAY 1.021277 (-7875 3800);
DISPLAY INVISIBLE (-7875 3800);
FORCEADD OFFPAGE..1
(-14100 0);
FORCEPROP 2 LAST $XR0 248 
J 0
(-14382 0);
DISPLAY 0.638298 (-14382 0);
PAINT MONO (-14382 0);
FORCEPROP 2 LAST PATH I70
J 0
(-14375 50);
DISPLAY 1.021277 (-14375 50);
DISPLAY INVISIBLE (-14375 50);
FORCEPROP 2 LAST CDS_LIB standard
J 0
(-14100 0);
PAINT MONO (-14100 0);
DISPLAY INVISIBLE (-14100 0);
FORCEPROP 1 LAST OFFPAGE TRUE
J 0
(-13775 -125);
DISPLAY 0.872340 (-13775 -125);
PAINT GREEN (-13775 -125);
DISPLAY INVISIBLE (-13775 -125);
FORCEPROP 1 LAST COMMENT_BODY TRUE
J 0
(-13975 -100);
DISPLAY 0.872340 (-13975 -100);
PAINT GREEN (-13975 -100);
DISPLAY INVISIBLE (-13975 -100);
FORCEADD OFFPAGE..5
(-14100 -100);
FORCEPROP 2 LAST $XR0 248 
J 0
(-14355 -100);
DISPLAY 0.638298 (-14355 -100);
PAINT MONO (-14355 -100);
FORCEPROP 2 LAST PATH I71
J 0
(-14375 -50);
DISPLAY 1.021277 (-14375 -50);
DISPLAY INVISIBLE (-14375 -50);
FORCEPROP 2 LAST CDS_LIB standard
J 0
(-14100 -100);
PAINT MONO (-14100 -100);
DISPLAY INVISIBLE (-14100 -100);
FORCEPROP 1 LAST COMMENT_BODY TRUE
J 0
(-14000 -175);
DISPLAY 0.872340 (-14000 -175);
PAINT PEACH (-14000 -175);
DISPLAY INVISIBLE (-14000 -175);
FORCEPROP 1 LAST OFFPAGE TRUE
J 0
(-13775 -225);
DISPLAY 0.872340 (-13775 -225);
PAINT GREEN (-13775 -225);
DISPLAY INVISIBLE (-13775 -225);
FORCEADD OFFPAGE..1
(-14825 -750);
FORCEPROP 2 LAST $XR0 214 
J 0
(-15077 -750);
DISPLAY 0.638298 (-15077 -750);
PAINT MONO (-15077 -750);
FORCEPROP 1 LAST COMMENT_BODY TRUE
J 0
(-14700 -850);
DISPLAY 0.872340 (-14700 -850);
PAINT GREEN (-14700 -850);
DISPLAY INVISIBLE (-14700 -850);
FORCEPROP 1 LAST OFFPAGE TRUE
J 0
(-14500 -875);
DISPLAY 0.872340 (-14500 -875);
PAINT GREEN (-14500 -875);
DISPLAY INVISIBLE (-14500 -875);
FORCEPROP 2 LAST PATH I72
J 0
(-15100 -700);
DISPLAY 1.021277 (-15100 -700);
DISPLAY INVISIBLE (-15100 -700);
FORCEPROP 2 LAST CDS_LIB standard
J 0
(-14825 -750);
PAINT MONO (-14825 -750);
DISPLAY INVISIBLE (-14825 -750);
FORCEADD UNIVERSAL_POWER..1
(-14125 -275);
FORCEPROP 3 LASTPIN (-14125 -325) SIG_NAME P3V3_AUX\g
J 0
(-14115 -315);
DISPLAY 0.659574 (-14115 -315);
PAINT MONO (-14115 -315);
DISPLAY INVISIBLE (-14115 -315);
FORCEPROP 1 LAST HDL_POWER P3V3_AUX
J 1
(-14125 -225);
DISPLAY 0.872340 (-14125 -225);
PAINT GREEN (-14125 -225);
FORCEPROP 2 LAST CDS_LIB logical_power
J 0
(-14125 -275);
PAINT MONO (-14125 -275);
DISPLAY INVISIBLE (-14125 -275);
FORCEPROP 1 LAST PATH I76
J 0
(-14075 -250);
DISPLAY 0.872340 (-14075 -250);
PAINT AQUA (-14075 -250);
DISPLAY INVISIBLE (-14075 -250);
FORCEADD Q_RES..2
(-14075 -975);
FORCEPROP 1 LAST PART_NUMBER CS21002FB06
J 0
(-14035 -1150);
DISPLAY 0.510638 (-14035 -1150);
DISPLAY INVISIBLE (-14035 -1150);
FORCEPROP 1 LAST VALUE 1K
J 0
(-14030 -900);
DISPLAY 0.510638 (-14030 -900);
FORCEPROP 1 LAST MATERIAL EMPTY
J 0
(-14035 -1050);
DISPLAY 0.510638 (-14035 -1050);
PAINT RED (-14035 -1050);
FORCEPROP 1 LAST WATTAGE 1/16W
J 0
(-14035 -1000);
DISPLAY 0.510638 (-14035 -1000);
FORCEPROP 1 LAST TOLERANCE 1%
J 0
(-14030 -950);
DISPLAY 0.510638 (-14030 -950);
FORCEPROP 1 LAST PACK_TYPE 0402LF
J 0
(-14035 -1100);
DISPLAY 0.510638 (-14035 -1100);
FORCEPROP 1 LAST $LOCATION R1814
J 0
(-14030 -850);
DISPLAY 0.787234 (-14030 -850);
FORCEPROP 1 LASTPIN (-14075 -875) $PN 1
J 0
(-14070 -913);
DISPLAY 0.787234 (-14070 -913);
FORCEPROP 1 LASTPIN (-14075 -1075) $PN 2
J 0
(-14070 -1065);
DISPLAY 0.787234 (-14070 -1065);
FORCEPROP 2 LAST CDS_LIB pure_quanta
J 0
(-14075 -975);
PAINT MONO (-14075 -975);
DISPLAY INVISIBLE (-14075 -975);
FORCEPROP 1 LAST PATH I77
J 0
(-14025 -800);
DISPLAY 0.978723 (-14025 -800);
PAINT WHITE (-14025 -800);
DISPLAY INVISIBLE (-14025 -800);
FORCEPROP 2 LAST CDS_LOCATION R1814
J 0
(-14025 -750);
DISPLAY 1.021277 (-14025 -750);
DISPLAY INVISIBLE (-14025 -750);
FORCEPROP 2 LAST $SEC 1
J 0
(-14025 -750);
DISPLAY 0.680851 (-14025 -750);
PAINT MONO (-14025 -750);
DISPLAY INVISIBLE (-14025 -750);
FORCEPROP 2 LAST CDS_SEC 1
J 0
(-14025 -750);
DISPLAY 1.021277 (-14025 -750);
DISPLAY INVISIBLE (-14025 -750);
FORCEADD UNIVERSAL_GND..1
(-14075 -1225);
FORCEPROP 3 LASTPIN (-14075 -1175) SIG_NAME GND\g
J 0
(-14065 -1165);
DISPLAY 0.659574 (-14065 -1165);
PAINT MONO (-14065 -1165);
DISPLAY INVISIBLE (-14065 -1165);
FORCEPROP 1 LAST PATH I78
J 0
(-14000 -1225);
DISPLAY 0.872340 (-14000 -1225);
PAINT AQUA (-14000 -1225);
DISPLAY INVISIBLE (-14000 -1225);
FORCEPROP 2 LAST CDS_LIB logical_power
J 0
(-14075 -1225);
PAINT MONO (-14075 -1225);
DISPLAY INVISIBLE (-14075 -1225);
FORCEPROP 1 LAST HDL_POWER GND
J 1
(-14050 -1300);
DISPLAY 0.872340 (-14050 -1300);
PAINT GREEN (-14050 -1300);
DISPLAY INVISIBLE (-14050 -1300);
FORCEADD Q_RES..2
(-14125 -500);
FORCEPROP 1 LAST PART_NUMBER CS31002FB08
J 0
(-14085 -675);
DISPLAY 0.404255 (-14085 -675);
DISPLAY INVISIBLE (-14085 -675);
FORCEPROP 1 LAST PACK_TYPE 0402LF
J 0
(-14085 -625);
DISPLAY 0.404255 (-14085 -625);
FORCEPROP 1 LAST VALUE 10K
J 0
(-14080 -425);
DISPLAY 0.404255 (-14080 -425);
FORCEPROP 1 LAST TOLERANCE 1%
J 0
(-14080 -475);
DISPLAY 0.404255 (-14080 -475);
FORCEPROP 1 LAST WATTAGE 1/16W
J 0
(-14085 -525);
DISPLAY 0.404255 (-14085 -525);
FORCEPROP 1 LAST MATERIAL EMPTY
J 0
(-14085 -575);
DISPLAY 0.404255 (-14085 -575);
PAINT RED (-14085 -575);
FORCEPROP 1 LAST $LOCATION R1813
J 0
(-14080 -375);
DISPLAY 0.638298 (-14080 -375);
FORCEPROP 1 LASTPIN (-14125 -400) $PN 1
J 0
(-14120 -438);
DISPLAY 0.787234 (-14120 -438);
FORCEPROP 1 LASTPIN (-14125 -600) $PN 2
J 0
(-14120 -590);
DISPLAY 0.787234 (-14120 -590);
FORCEPROP 1 LAST PATH I79
J 0
(-14075 -325);
DISPLAY 0.978723 (-14075 -325);
PAINT WHITE (-14075 -325);
DISPLAY INVISIBLE (-14075 -325);
FORCEPROP 2 LAST CDS_LIB pure_quanta
J 0
(-14125 -500);
PAINT MONO (-14125 -500);
DISPLAY INVISIBLE (-14125 -500);
FORCEPROP 2 LAST CDS_LOCATION R1813
J 0
(-14075 -275);
DISPLAY 1.021277 (-14075 -275);
DISPLAY INVISIBLE (-14075 -275);
FORCEPROP 2 LAST $SEC 1
J 0
(-14075 -275);
DISPLAY 0.680851 (-14075 -275);
PAINT MONO (-14075 -275);
DISPLAY INVISIBLE (-14075 -275);
FORCEPROP 2 LAST CDS_SEC 1
J 0
(-14075 -275);
DISPLAY 1.021277 (-14075 -275);
DISPLAY INVISIBLE (-14075 -275);
FORCEADD UNIVERSAL_GND..1
R 2
(-9000 3225);
FORCEPROP 3 LASTPIN (-9000 3275) SIG_NAME GND\g
J 0
(-8990 3285);
DISPLAY 0.659574 (-8990 3285);
PAINT MONO (-8990 3285);
DISPLAY INVISIBLE (-8990 3285);
FORCEPROP 1 LAST HDL_POWER GND
J 1
(-9025 3150);
DISPLAY 0.872340 (-9025 3150);
PAINT GREEN (-9025 3150);
DISPLAY INVISIBLE (-9025 3150);
FORCEPROP 2 LAST CDS_LIB logical_power
R 3
J 0
(-9000 3225);
PAINT MONO (-9000 3225);
DISPLAY INVISIBLE (-9000 3225);
FORCEPROP 1 LAST PATH I8
J 2
(-9075 3225);
DISPLAY 0.872340 (-9075 3225);
PAINT AQUA (-9075 3225);
DISPLAY INVISIBLE (-9075 3225);
FORCEADD Q_RES..1
(-8625 2925);
FORCEPROP 1 LAST PART_NUMBER CS00002JB13
J 0
(-8725 2975);
DISPLAY 0.404255 (-8725 2975);
DISPLAY INVISIBLE (-8725 2975);
FORCEPROP 1 LAST MATERIAL EMPTY
J 0
(-8375 2925);
DISPLAY 0.510638 (-8375 2925);
PAINT RED (-8375 2925);
FORCEPROP 1 LAST TOLERANCE 5%
J 0
(-8450 2925);
DISPLAY 0.510638 (-8450 2925);
FORCEPROP 1 LAST WATTAGE 1/16W
J 2
(-8500 3000);
DISPLAY 0.404255 (-8500 3000);
FORCEPROP 1 LAST PACK_TYPE 0402LF
J 0
(-8725 3000);
DISPLAY 0.404255 (-8725 3000);
FORCEPROP 1 LAST VALUE 0
J 2
(-8475 2925);
DISPLAY 0.510638 (-8475 2925);
FORCEPROP 1 LAST $LOCATION R1832
J 0
(-8875 2925);
DISPLAY 0.638298 (-8875 2925);
FORCEPROP 1 LASTPIN (-8725 2925) $PN 1
J 0
(-8713 2937);
DISPLAY 0.787234 (-8713 2937);
FORCEPROP 1 LASTPIN (-8525 2925) $PN 2
J 0
(-8563 2937);
DISPLAY 0.787234 (-8563 2937);
FORCEPROP 1 LAST PATH I80
J 0
(-8675 3075);
DISPLAY 0.978723 (-8675 3075);
PAINT WHITE (-8675 3075);
DISPLAY INVISIBLE (-8675 3075);
FORCEPROP 2 LAST CDS_LIB pure_quanta
J 0
(-8625 2925);
PAINT MONO (-8625 2925);
DISPLAY INVISIBLE (-8625 2925);
FORCEPROP 2 LAST CDS_LOCATION R1832
J 0
(-8675 3125);
DISPLAY 1.021277 (-8675 3125);
DISPLAY INVISIBLE (-8675 3125);
FORCEPROP 2 LAST $SEC 1
J 0
(-8675 3125);
DISPLAY 0.680851 (-8675 3125);
PAINT MONO (-8675 3125);
DISPLAY INVISIBLE (-8675 3125);
FORCEPROP 2 LAST CDS_SEC 1
J 0
(-8675 3125);
DISPLAY 1.021277 (-8675 3125);
DISPLAY INVISIBLE (-8675 3125);
FORCEADD OFFPAGE..4
(-7550 2925);
FORCEPROP 2 LAST $XR0 215 
J 0
(-7364 2925);
DISPLAY 0.638298 (-7364 2925);
PAINT MONO (-7364 2925);
FORCEPROP 2 LAST PATH I81
J 0
(-7350 2975);
DISPLAY 1.021277 (-7350 2975);
DISPLAY INVISIBLE (-7350 2975);
FORCEPROP 1 LAST OFFPAGE TRUE
J 0
(-7225 2800);
DISPLAY 1.170213 (-7225 2800);
PAINT GREEN (-7225 2800);
DISPLAY INVISIBLE (-7225 2800);
FORCEPROP 1 LAST COMMENT_BODY TRUE
J 0
(-7575 2825);
DISPLAY 1.170213 (-7575 2825);
PAINT GREEN (-7575 2825);
DISPLAY INVISIBLE (-7575 2825);
FORCEPROP 2 LAST CDS_LIB standard
J 0
(-7550 2925);
PAINT MONO (-7550 2925);
DISPLAY INVISIBLE (-7550 2925);
FORCEADD Q_RES..1
(-8650 1400);
FORCEPROP 1 LAST PART_NUMBER CS00002JB13
J 0
(-8750 1450);
DISPLAY 0.404255 (-8750 1450);
DISPLAY INVISIBLE (-8750 1450);
FORCEPROP 1 LAST TOLERANCE 5%
J 0
(-8475 1400);
DISPLAY 0.510638 (-8475 1400);
FORCEPROP 1 LAST PACK_TYPE 0402LF
J 0
(-8750 1475);
DISPLAY 0.404255 (-8750 1475);
FORCEPROP 1 LAST WATTAGE 1/16W
J 2
(-8525 1475);
DISPLAY 0.404255 (-8525 1475);
FORCEPROP 1 LAST MATERIAL EMPTY
J 0
(-8400 1400);
DISPLAY 0.510638 (-8400 1400);
PAINT RED (-8400 1400);
FORCEPROP 1 LAST VALUE 0
J 2
(-8500 1400);
DISPLAY 0.510638 (-8500 1400);
FORCEPROP 1 LAST $LOCATION R1831
J 0
(-8900 1400);
DISPLAY 0.638298 (-8900 1400);
FORCEPROP 1 LASTPIN (-8750 1400) $PN 1
J 0
(-8738 1412);
DISPLAY 0.787234 (-8738 1412);
FORCEPROP 1 LASTPIN (-8550 1400) $PN 2
J 0
(-8588 1412);
DISPLAY 0.787234 (-8588 1412);
FORCEPROP 2 LAST CDS_LIB pure_quanta
J 0
(-8650 1400);
PAINT MONO (-8650 1400);
DISPLAY INVISIBLE (-8650 1400);
FORCEPROP 1 LAST PATH I82
J 0
(-8700 1550);
DISPLAY 0.978723 (-8700 1550);
PAINT WHITE (-8700 1550);
DISPLAY INVISIBLE (-8700 1550);
FORCEPROP 2 LAST CDS_LOCATION R1831
J 0
(-8700 1600);
DISPLAY 1.021277 (-8700 1600);
DISPLAY INVISIBLE (-8700 1600);
FORCEPROP 2 LAST $SEC 1
J 0
(-8700 1600);
DISPLAY 0.680851 (-8700 1600);
PAINT MONO (-8700 1600);
DISPLAY INVISIBLE (-8700 1600);
FORCEPROP 2 LAST CDS_SEC 1
J 0
(-8700 1600);
DISPLAY 1.021277 (-8700 1600);
DISPLAY INVISIBLE (-8700 1600);
FORCEADD OFFPAGE..2
(-7575 1400);
FORCEPROP 2 LAST $XR0 215 
J 0
(-7386 1400);
DISPLAY 0.638298 (-7386 1400);
PAINT MONO (-7386 1400);
FORCEPROP 1 LAST COMMENT_BODY TRUE
J 0
(-7620 1305);
DISPLAY 0.872340 (-7620 1305);
PAINT GREEN (-7620 1305);
DISPLAY INVISIBLE (-7620 1305);
FORCEPROP 1 LAST OFFPAGE TRUE
J 0
(-7250 1275);
DISPLAY 0.872340 (-7250 1275);
PAINT GREEN (-7250 1275);
DISPLAY INVISIBLE (-7250 1275);
FORCEPROP 2 LAST PATH I83
J 0
(-7400 1475);
DISPLAY 1.021277 (-7400 1475);
DISPLAY INVISIBLE (-7400 1475);
FORCEPROP 2 LAST CDS_LIB standard
J 0
(-7575 1400);
PAINT MONO (-7575 1400);
DISPLAY INVISIBLE (-7575 1400);
FORCEADD OFFPAGE..2
(-7100 -100);
FORCEPROP 2 LAST $XR0 134 
J 0
(-6911 -100);
DISPLAY 0.638298 (-6911 -100);
PAINT MONO (-6911 -100);
FORCEPROP 2 LAST CDS_LIB standard
J 0
(-7100 -100);
DISPLAY INVISIBLE (-7100 -100);
FORCEPROP 2 LAST PATH I84
J 0
(-6900 -50);
DISPLAY 1.021277 (-6900 -50);
DISPLAY INVISIBLE (-6900 -50);
FORCEPROP 1 LAST COMMENT_BODY TRUE
J 0
(-7145 -195);
DISPLAY 0.872340 (-7145 -195);
PAINT GREEN (-7145 -195);
DISPLAY INVISIBLE (-7145 -195);
FORCEPROP 1 LAST OFFPAGE TRUE
J 0
(-6775 -225);
DISPLAY 0.872340 (-6775 -225);
PAINT GREEN (-6775 -225);
DISPLAY INVISIBLE (-6775 -225);
FORCEADD OFFPAGE..2
(-7100 -400);
FORCEPROP 2 LAST $XR0 221 
J 0
(-6911 -400);
DISPLAY 0.638298 (-6911 -400);
PAINT MONO (-6911 -400);
FORCEPROP 2 LAST CDS_LIB standard
J 0
(-7100 -400);
DISPLAY INVISIBLE (-7100 -400);
FORCEPROP 2 LAST PATH I85
J 0
(-6900 -350);
DISPLAY 1.021277 (-6900 -350);
DISPLAY INVISIBLE (-6900 -350);
FORCEPROP 1 LAST COMMENT_BODY TRUE
J 0
(-7145 -495);
DISPLAY 0.872340 (-7145 -495);
PAINT GREEN (-7145 -495);
DISPLAY INVISIBLE (-7145 -495);
FORCEPROP 1 LAST OFFPAGE TRUE
J 0
(-6775 -525);
DISPLAY 0.872340 (-6775 -525);
PAINT GREEN (-6775 -525);
DISPLAY INVISIBLE (-6775 -525);
FORCEADD UNIVERSAL_POWER..1
(-8400 3975);
FORCEPROP 3 LASTPIN (-8400 3925) SIG_NAME P3V3_AUX\g
J 0
(-8390 3935);
DISPLAY 0.659574 (-8390 3935);
PAINT MONO (-8390 3935);
DISPLAY INVISIBLE (-8390 3935);
FORCEPROP 1 LAST HDL_POWER P3V3_AUX
J 1
(-8400 4025);
DISPLAY 0.872340 (-8400 4025);
PAINT GREEN (-8400 4025);
FORCEPROP 1 LAST PATH I86
J 0
(-8350 4000);
DISPLAY 0.872340 (-8350 4000);
PAINT AQUA (-8350 4000);
DISPLAY INVISIBLE (-8350 4000);
FORCEPROP 2 LAST CDS_LIB logical_power
J 0
(-8400 3975);
DISPLAY INVISIBLE (-8400 3975);
FORCEADD Q_RES..2
(-8400 3575);
FORCEPROP 1 LAST PART_NUMBER CS21002FB06
J 0
(-8360 3450);
DISPLAY 0.510638 (-8360 3450);
DISPLAY INVISIBLE (-8360 3450);
FORCEPROP 1 LAST MATERIAL CHIP
J 0
(-8360 3500);
DISPLAY 0.510638 (-8360 3500);
FORCEPROP 1 LAST WATTAGE 1/16W
J 0
(-8360 3550);
DISPLAY 0.510638 (-8360 3550);
FORCEPROP 1 LAST TOLERANCE 1%
J 0
(-8355 3600);
DISPLAY 0.510638 (-8355 3600);
FORCEPROP 1 LAST PACK_TYPE 0402LF
J 0
(-8350 3450);
DISPLAY 0.510638 (-8350 3450);
FORCEPROP 1 LAST VALUE 1K
J 0
(-8355 3650);
DISPLAY 0.510638 (-8355 3650);
FORCEPROP 1 LAST $LOCATION R2506
J 0
(-8355 3700);
DISPLAY 0.638298 (-8355 3700);
FORCEPROP 1 LAST PATH I87
J 0
(-8350 3750);
DISPLAY 0.978723 (-8350 3750);
PAINT WHITE (-8350 3750);
DISPLAY INVISIBLE (-8350 3750);
FORCEPROP 2 LAST CDS_LIB pure_quanta
J 0
(-8400 3575);
DISPLAY INVISIBLE (-8400 3575);
FORCEPROP 0 LAST CDS_LOCATION R2506
J 0
(-8350 3750);
DISPLAY 1.021277 (-8350 3750);
DISPLAY INVISIBLE (-8350 3750);
FORCEPROP 0 LAST $SEC 1
J 0
(-8350 3750);
DISPLAY 0.680851 (-8350 3750);
PAINT MONO (-8350 3750);
DISPLAY INVISIBLE (-8350 3750);
FORCEPROP 0 LAST CDS_SEC 1
J 0
(-8350 3750);
DISPLAY 1.021277 (-8350 3750);
DISPLAY INVISIBLE (-8350 3750);
FORCEPROP 1 LASTPIN (-8400 3675) $PN 1
J 0
(-8395 3637);
DISPLAY 0.787234 (-8395 3637);
PAINT MONO (-8395 3637);
DISPLAY INVISIBLE (-8395 3637);
FORCEPROP 1 LASTPIN (-8400 3475) $PN 2
J 0
(-8395 3485);
DISPLAY 0.787234 (-8395 3485);
PAINT MONO (-8395 3485);
DISPLAY INVISIBLE (-8395 3485);
FORCEADD Q_RES..2
(-8175 3575);
FORCEPROP 1 LAST PART_NUMBER CS21002FB06
J 0
(-8135 3450);
DISPLAY 0.510638 (-8135 3450);
DISPLAY INVISIBLE (-8135 3450);
FORCEPROP 1 LAST VALUE 1K
J 0
(-8130 3650);
DISPLAY 0.510638 (-8130 3650);
FORCEPROP 1 LAST MATERIAL CHIP
J 0
(-8135 3500);
DISPLAY 0.510638 (-8135 3500);
FORCEPROP 1 LAST PACK_TYPE 0402LF
J 0
(-8125 3450);
DISPLAY 0.510638 (-8125 3450);
FORCEPROP 1 LAST TOLERANCE 1%
J 0
(-8130 3600);
DISPLAY 0.510638 (-8130 3600);
FORCEPROP 1 LAST WATTAGE 1/16W
J 0
(-8135 3550);
DISPLAY 0.510638 (-8135 3550);
FORCEPROP 1 LAST $LOCATION R2507
J 0
(-8130 3700);
DISPLAY 0.638298 (-8130 3700);
FORCEPROP 2 LAST CDS_LIB pure_quanta
J 0
(-8175 3575);
DISPLAY INVISIBLE (-8175 3575);
FORCEPROP 1 LAST PATH I88
J 0
(-8125 3750);
DISPLAY 0.978723 (-8125 3750);
PAINT WHITE (-8125 3750);
DISPLAY INVISIBLE (-8125 3750);
FORCEPROP 0 LAST CDS_LOCATION R2507
J 0
(-8125 3750);
DISPLAY 1.021277 (-8125 3750);
DISPLAY INVISIBLE (-8125 3750);
FORCEPROP 0 LAST $SEC 1
J 0
(-8125 3750);
DISPLAY 0.680851 (-8125 3750);
PAINT MONO (-8125 3750);
DISPLAY INVISIBLE (-8125 3750);
FORCEPROP 0 LAST CDS_SEC 1
J 0
(-8125 3750);
DISPLAY 1.021277 (-8125 3750);
DISPLAY INVISIBLE (-8125 3750);
FORCEPROP 1 LASTPIN (-8175 3675) $PN 1
J 0
(-8170 3637);
DISPLAY 0.787234 (-8170 3637);
PAINT MONO (-8170 3637);
DISPLAY INVISIBLE (-8170 3637);
FORCEPROP 1 LASTPIN (-8175 3475) $PN 2
J 0
(-8170 3485);
DISPLAY 0.787234 (-8170 3485);
PAINT MONO (-8170 3485);
DISPLAY INVISIBLE (-8170 3485);
FORCEADD Q_RES..1
(-9400 3300);
FORCEPROP 1 LAST PART_NUMBER CS21002FB06
J 0
(-9575 3375);
DISPLAY 0.510638 (-9575 3375);
DISPLAY INVISIBLE (-9575 3375);
FORCEPROP 1 LAST MATERIAL EMPTY
J 0
(-9125 3300);
DISPLAY 0.510638 (-9125 3300);
PAINT RED (-9125 3300);
FORCEPROP 1 LAST VALUE 1K
J 2
(-9225 3300);
DISPLAY 0.510638 (-9225 3300);
FORCEPROP 1 LAST TOLERANCE 1%
J 0
(-9200 3300);
DISPLAY 0.510638 (-9200 3300);
FORCEPROP 1 LAST $LOCATION R2514
J 0
(-9625 3300);
DISPLAY 0.638298 (-9625 3300);
FORCEPROP 1 LASTPIN (-9500 3300) $PN 1
J 0
(-9488 3312);
DISPLAY 0.787234 (-9488 3312);
PAINT MONO (-9488 3312);
FORCEPROP 1 LASTPIN (-9300 3300) $PN 2
J 0
(-9338 3312);
DISPLAY 0.787234 (-9338 3312);
PAINT MONO (-9338 3312);
FORCEPROP 1 LAST PACK_TYPE 0402LF
J 0
(-9300 3425);
DISPLAY 0.510638 (-9300 3425);
DISPLAY INVISIBLE (-9300 3425);
FORCEPROP 1 LAST WATTAGE 1/16W
J 2
(-9325 3425);
DISPLAY 0.510638 (-9325 3425);
DISPLAY INVISIBLE (-9325 3425);
FORCEPROP 2 LAST CDS_LIB pure_quanta
J 0
(-9400 3300);
DISPLAY INVISIBLE (-9400 3300);
FORCEPROP 1 LAST PATH I89
J 0
(-9450 3450);
DISPLAY 0.978723 (-9450 3450);
PAINT WHITE (-9450 3450);
DISPLAY INVISIBLE (-9450 3450);
FORCEPROP 0 LAST CDS_LOCATION R2514
J 0
(-9625 3350);
DISPLAY 1.021277 (-9625 3350);
DISPLAY INVISIBLE (-9625 3350);
FORCEPROP 0 LAST $SEC 1
J 0
(-9625 3350);
DISPLAY 0.680851 (-9625 3350);
PAINT MONO (-9625 3350);
DISPLAY INVISIBLE (-9625 3350);
FORCEPROP 0 LAST CDS_SEC 1
J 0
(-9625 3350);
DISPLAY 1.021277 (-9625 3350);
DISPLAY INVISIBLE (-9625 3350);
FORCEADD UNIVERSAL_POWER..1
(-10100 4000);
FORCEPROP 3 LASTPIN (-10100 3950) SIG_NAME P3V3_AUX\g
J 0
(-10090 3960);
DISPLAY 0.659574 (-10090 3960);
PAINT MONO (-10090 3960);
DISPLAY INVISIBLE (-10090 3960);
FORCEPROP 1 LAST HDL_POWER P3V3_AUX
J 1
(-10100 4050);
DISPLAY 0.872340 (-10100 4050);
PAINT GREEN (-10100 4050);
FORCEPROP 2 LAST CDS_LIB logical_power
J 0
(-10100 4000);
PAINT MONO (-10100 4000);
DISPLAY INVISIBLE (-10100 4000);
FORCEPROP 1 LAST PATH I9
J 0
(-10050 4025);
DISPLAY 0.872340 (-10050 4025);
PAINT AQUA (-10050 4025);
DISPLAY INVISIBLE (-10050 4025);
FORCEADD Q_RES..1
(-9450 1725);
FORCEPROP 1 LAST PART_NUMBER CS00002JB13
J 0
(-9550 1800);
DISPLAY 0.404255 (-9550 1800);
DISPLAY INVISIBLE (-9550 1800);
FORCEPROP 1 LAST TOLERANCE 5%
J 0
(-9225 1725);
DISPLAY 0.510638 (-9225 1725);
FORCEPROP 1 LAST MATERIAL CHIP
J 0
(-9150 1725);
DISPLAY 0.510638 (-9150 1725);
FORCEPROP 1 LAST VALUE 0
J 2
(-9275 1725);
DISPLAY 0.510638 (-9275 1725);
FORCEPROP 1 LAST $LOCATION R2513
J 0
(-9700 1725);
DISPLAY 0.638298 (-9700 1725);
FORCEPROP 1 LASTPIN (-9550 1725) $PN 1
J 0
(-9538 1737);
DISPLAY 0.787234 (-9538 1737);
PAINT MONO (-9538 1737);
FORCEPROP 1 LASTPIN (-9350 1725) $PN 2
J 0
(-9388 1737);
DISPLAY 0.787234 (-9388 1737);
PAINT MONO (-9388 1737);
FORCEPROP 2 LAST CDS_LIB pure_quanta
J 0
(-9450 1725);
DISPLAY INVISIBLE (-9450 1725);
FORCEPROP 1 LAST PATH I90
J 0
(-9500 1875);
DISPLAY 0.978723 (-9500 1875);
PAINT WHITE (-9500 1875);
DISPLAY INVISIBLE (-9500 1875);
FORCEPROP 1 LAST WATTAGE 1/16W
J 2
(-9325 1825);
DISPLAY 0.404255 (-9325 1825);
DISPLAY INVISIBLE (-9325 1825);
FORCEPROP 1 LAST PACK_TYPE 0402LF
J 0
(-9550 1825);
DISPLAY 0.404255 (-9550 1825);
DISPLAY INVISIBLE (-9550 1825);
FORCEPROP 0 LAST CDS_LOCATION R2513
J 0
(-9700 1775);
DISPLAY 1.021277 (-9700 1775);
DISPLAY INVISIBLE (-9700 1775);
FORCEPROP 0 LAST $SEC 1
J 0
(-9700 1775);
DISPLAY 0.680851 (-9700 1775);
PAINT MONO (-9700 1775);
DISPLAY INVISIBLE (-9700 1775);
FORCEPROP 0 LAST CDS_SEC 1
J 0
(-9700 1775);
DISPLAY 1.021277 (-9700 1775);
DISPLAY INVISIBLE (-9700 1775);
FORCEADD Q_RES..2
(-10125 2175);
FORCEPROP 1 LAST PART_NUMBER CS04992FB07
J 0
(-10085 2050);
DISPLAY 0.404255 (-10085 2050);
DISPLAY INVISIBLE (-10085 2050);
FORCEPROP 1 LAST TOLERANCE 1%
J 0
(-10080 2200);
DISPLAY 0.510638 (-10080 2200);
FORCEPROP 1 LAST VALUE 49.9
J 0
(-10080 2250);
DISPLAY 0.510638 (-10080 2250);
FORCEPROP 1 LAST WATTAGE 1/16W
J 0
(-10085 2150);
DISPLAY 0.510638 (-10085 2150);
FORCEPROP 1 LAST MATERIAL CHIP
J 0
(-10085 2100);
DISPLAY 0.510638 (-10085 2100);
FORCEPROP 1 LAST PACK_TYPE 0402LF
J 0
(-10085 2000);
DISPLAY 0.510638 (-10085 2000);
FORCEPROP 1 LAST $LOCATION R2512
J 0
(-10080 2300);
DISPLAY 0.978723 (-10080 2300);
FORCEPROP 1 LASTPIN (-10125 2275) $PN 1
J 0
(-10120 2237);
DISPLAY 0.787234 (-10120 2237);
PAINT MONO (-10120 2237);
FORCEPROP 1 LASTPIN (-10125 2075) $PN 2
J 0
(-10120 2085);
DISPLAY 0.787234 (-10120 2085);
PAINT MONO (-10120 2085);
FORCEPROP 1 LAST PATH I91
J 0
(-10075 2350);
DISPLAY 0.978723 (-10075 2350);
PAINT WHITE (-10075 2350);
DISPLAY INVISIBLE (-10075 2350);
FORCEPROP 2 LAST CDS_LIB pure_quanta
J 2
(-10125 2175);
DISPLAY INVISIBLE (-10125 2175);
FORCEPROP 0 LAST CDS_LOCATION R2512
J 0
(-10075 2350);
DISPLAY 1.021277 (-10075 2350);
DISPLAY INVISIBLE (-10075 2350);
FORCEPROP 0 LAST $SEC 1
J 0
(-10075 2350);
DISPLAY 0.680851 (-10075 2350);
PAINT MONO (-10075 2350);
DISPLAY INVISIBLE (-10075 2350);
FORCEPROP 0 LAST CDS_SEC 1
J 0
(-10075 2350);
DISPLAY 1.021277 (-10075 2350);
DISPLAY INVISIBLE (-10075 2350);
FORCEADD UNIVERSAL_POWER..1
(-10125 2525);
FORCEPROP 3 LASTPIN (-10125 2475) SIG_NAME P1V05_PCH_AUX\g
J 0
(-10115 2485);
DISPLAY 0.659574 (-10115 2485);
PAINT MONO (-10115 2485);
DISPLAY INVISIBLE (-10115 2485);
FORCEPROP 1 LAST HDL_POWER P1V05_PCH_AUX
J 1
(-10125 2575);
DISPLAY 0.872340 (-10125 2575);
PAINT GREEN (-10125 2575);
FORCEPROP 2 LAST CDS_LIB logical_power
J 0
(-10125 2525);
DISPLAY INVISIBLE (-10125 2525);
FORCEPROP 1 LAST PATH I92
J 0
(-10075 2550);
DISPLAY 0.872340 (-10075 2550);
PAINT AQUA (-10075 2550);
DISPLAY INVISIBLE (-10075 2550);
FORCEADD Q_CAP..2
(-9450 2075);
FORCEPROP 1 LAST PART_NUMBER CH4104K1B00
J 1
(-9450 2175);
DISPLAY 0.510638 (-9450 2175);
DISPLAY INVISIBLE (-9450 2175);
FORCEPROP 1 LAST TOLERANCE 10%
J 2
(-9100 2075);
DISPLAY 0.510638 (-9100 2075);
FORCEPROP 1 LAST VALUE 0.1UF
J 2
(-9200 2075);
DISPLAY 0.510638 (-9200 2075);
FORCEPROP 1 LAST VOLTAGE 25V
J 0
(-9350 2225);
DISPLAY 0.510638 (-9350 2225);
FORCEPROP 1 LAST PACK_TYPE 0402
J 1
(-9425 2225);
DISPLAY 0.510638 (-9425 2225);
FORCEPROP 1 LAST MATERIAL X7R
J 0
(-9575 2225);
DISPLAY 0.510638 (-9575 2225);
FORCEPROP 1 LAST $LOCATION C1664
J 1
(-9625 2075);
DISPLAY 0.638298 (-9625 2075);
FORCEPROP 1 LASTPIN (-9550 2075) $PN 1
J 0
(-9560 2090);
DISPLAY 0.787234 (-9560 2090);
PAINT MONO (-9560 2090);
FORCEPROP 1 LASTPIN (-9350 2075) $PN 2
J 0
(-9365 2090);
DISPLAY 0.787234 (-9365 2090);
PAINT MONO (-9365 2090);
FORCEPROP 2 LAST CDS_LIB pure_quanta
J 0
(-9450 2075);
DISPLAY INVISIBLE (-9450 2075);
FORCEPROP 1 LAST PATH I93
J 0
(-9450 2275);
DISPLAY 0.978723 (-9450 2275);
PAINT WHITE (-9450 2275);
DISPLAY INVISIBLE (-9450 2275);
FORCEPROP 0 LAST CDS_LOCATION C1664
J 0
(-9350 2250);
DISPLAY 1.021277 (-9350 2250);
DISPLAY INVISIBLE (-9350 2250);
FORCEPROP 0 LAST $SEC 1
J 0
(-9350 2250);
DISPLAY 0.680851 (-9350 2250);
PAINT MONO (-9350 2250);
DISPLAY INVISIBLE (-9350 2250);
FORCEPROP 0 LAST CDS_SEC 1
J 0
(-9350 2250);
DISPLAY 1.021277 (-9350 2250);
DISPLAY INVISIBLE (-9350 2250);
FORCEADD OFFPAGE..2
(-11150 0);
FORCEPROP 2 LAST $XR0 239 
J 0
(-10961 0);
DISPLAY 0.638298 (-10961 0);
PAINT MONO (-10961 0);
FORCEPROP 2 LAST PATH I94
J 0
(-10950 50);
DISPLAY 1.021277 (-10950 50);
DISPLAY INVISIBLE (-10950 50);
FORCEPROP 2 LAST CDS_LIB standard
J 0
(-11150 0);
PAINT MONO (-11150 0);
DISPLAY INVISIBLE (-11150 0);
FORCEPROP 1 LAST COMMENT_BODY TRUE
J 0
(-11195 -95);
DISPLAY 0.872340 (-11195 -95);
PAINT GREEN (-11195 -95);
DISPLAY INVISIBLE (-11195 -95);
FORCEPROP 1 LAST OFFPAGE TRUE
J 0
(-10825 -125);
DISPLAY 0.872340 (-10825 -125);
PAINT GREEN (-10825 -125);
DISPLAY INVISIBLE (-10825 -125);
FORCEADD OFFPAGE..2
(-7100 0);
FORCEPROP 2 LAST $XR0 239 
J 0
(-6911 0);
DISPLAY 0.638298 (-6911 0);
PAINT MONO (-6911 0);
FORCEPROP 2 LAST PATH I95
J 0
(-6900 50);
DISPLAY 1.021277 (-6900 50);
DISPLAY INVISIBLE (-6900 50);
FORCEPROP 1 LAST OFFPAGE TRUE
J 0
(-6775 -125);
DISPLAY 0.872340 (-6775 -125);
PAINT GREEN (-6775 -125);
DISPLAY INVISIBLE (-6775 -125);
FORCEPROP 1 LAST COMMENT_BODY TRUE
J 0
(-7145 -95);
DISPLAY 0.872340 (-7145 -95);
PAINT GREEN (-7145 -95);
DISPLAY INVISIBLE (-7145 -95);
FORCEPROP 2 LAST CDS_LIB standard
J 0
(-7100 0);
PAINT MONO (-7100 0);
DISPLAY INVISIBLE (-7100 0);
FORCEADD DNS..2
(-14075 -1000);
PAINT RED (-14075 -1000);
FORCEPROP 2 LAST CDS_LIB mstr_misc
J 0
(-14075 -1000);
DISPLAY INVISIBLE (-14075 -1000);
FORCEPROP 1 LAST COMMENT_BODY TRUE
J 0
(-14075 -1000);
DISPLAY INVISIBLE (-14075 -1000);
FORCEADD DNS..2
(-14120 -530);
PAINT RED (-14120 -530);
FORCEPROP 1 LAST COMMENT_BODY TRUE
J 0
(-14120 -530);
DISPLAY INVISIBLE (-14120 -530);
FORCEPROP 2 LAST CDS_LIB mstr_misc
J 0
(-14120 -530);
PAINT MONO (-14120 -530);
DISPLAY INVISIBLE (-14120 -530);
FORCEADD DESIGN_NOTE..1
(-10525 -1275);
FORCEPROP 0 LAST S1 FM_JTAG_BMC_MUX_SEL == LOW (DEFAULT) ,  BMC TO CPLD
J 0
(-10725 -1425);
DISPLAY 1.021277 (-10725 -1425);
PAINT SKYBLUE (-10725 -1425);
FORCEPROP 0 LAST S2 FM_JTAG_BMC_MUX_SEL == HIGH ,  BMC TO CPU/PCH
J 0
(-10725 -1500);
DISPLAY 1.021277 (-10725 -1500);
PAINT SKYBLUE (-10725 -1500);
FORCEPROP 2 LAST CDS_LIB logical_power
J 0
(-10525 -1275);
PAINT MONO (-10525 -1275);
DISPLAY INVISIBLE (-10525 -1275);
FORCEPROP 1 LAST COMMENT_BODY TRUE
J 0
(-10500 -1175);
DISPLAY 0.978723 (-10500 -1175);
DISPLAY INVISIBLE (-10500 -1175);
FORCEADD DNS..2
(-8645 1395);
PAINT RED (-8645 1395);
FORCEPROP 1 LAST COMMENT_BODY TRUE
J 0
(-8645 1395);
DISPLAY INVISIBLE (-8645 1395);
FORCEPROP 2 LAST CDS_LIB mstr_misc
J 0
(-8645 1395);
PAINT MONO (-8645 1395);
DISPLAY INVISIBLE (-8645 1395);
FORCEADD DNS..2
(-9375 3300);
PAINT RED (-9375 3300);
FORCEPROP 2 LAST CDS_LIB mstr_misc
J 0
(-9375 3300);
DISPLAY INVISIBLE (-9375 3300);
FORCEPROP 1 LAST COMMENT_BODY TRUE
J 0
(-9375 3300);
DISPLAY INVISIBLE (-9375 3300);
FORCEADD DNS..2
(-8620 2920);
PAINT RED (-8620 2920);
FORCEPROP 1 LAST COMMENT_BODY TRUE
J 0
(-8620 2920);
DISPLAY INVISIBLE (-8620 2920);
FORCEPROP 2 LAST CDS_LIB mstr_misc
J 0
(-8620 2920);
PAINT MONO (-8620 2920);
DISPLAY INVISIBLE (-8620 2920);
FORCEADD QUANTA_TITLE_BLOCK_C..1
(-6500 -2200);
FORCEPROP 0 LAST CDS_CON_LAST_MODIFIED Fri Aug 25 14:04:06 2023
J 0
(-8385 -2185);
PAINT MONO (-8385 -2185);
DISPLAY INVISIBLE (-8385 -2185);
FORCEPROP 2 LAST CUSTOM_TXT_CDS <XR_PAGE_TITLE>
J 0
(-14390 3050);
DISPLAY 0.638298 (-14390 3050);
PAINT PINK (-14390 3050);
DISPLAY INVISIBLE (-14390 3050);
FORCEPROP 2 LAST CUSTOM_TXT_CDS <CON_LAST_MODIFIED>
J 0
(-8385 -2185);
DISPLAY 0.978723 (-8385 -2185);
FORCEPROP 2 LAST CUSTOM_TXT_CDS <CON_PAGE_NUM> OF <CON_TOTAL_PAGES>
J 0
(-6946 -2182);
DISPLAY 0.978723 (-6946 -2182);
FORCEPROP 2 LAST CUSTOM_TXT_CDS <Q_REV>
J 0
(-6684 -2097);
DISPLAY 1.212766 (-6684 -2097);
FORCEPROP 2 LAST CUSTOM_TXT_CDS <Q_PROJ>
J 0
(-8882 -2098);
DISPLAY 1.212766 (-8882 -2098);
FORCEPROP 2 LAST CUSTOM_TXT_CDS <Q_NUMBER>
J 0
(-7903 -2097);
DISPLAY 1.212766 (-7903 -2097);
FORCEPROP 2 LAST CUSTOM_TXT_CDS <NAME_1>
J 0
(-9675 -2025);
FORCEPROP 2 LAST CUSTOM_TXT_CDS <NAME_2>
J 0
(-9675 -2150);
FORCEPROP 1 LAST Q_TITLE SCM REMOTE JTAG LOGIC
J 0
(-15791 -2174);
DISPLAY 2.446809 (-15791 -2174);
PAINT GREEN (-15791 -2174);
FORCEPROP 1 LAST Q_DEPT 
J 1
(-10263 -2151);
DISPLAY 1.957447 (-10263 -2151);
PAINT GREEN (-10263 -2151);
FORCEPROP 2 LAST CDS_XR_PAGE_TITLE CR-239 : @S9S_MB_2U_LIB.S9S_MB_2U(SCH_1):PAGE239
J 0
(-14390 3050);
DISPLAY 0.638298 (-14390 3050);
PAINT PINK (-14390 3050);
DISPLAY INVISIBLE (-14390 3050);
FORCEPROP 2 LAST CDS_LIB pure_quanta
J 0
(-6500 -2200);
PAINT MONO (-6500 -2200);
DISPLAY INVISIBLE (-6500 -2200);
FORCEPROP 1 LAST CDS_LMAN_SYM_OUTLINE -9475,6775,100,-125
J 0
(-6500 -2200);
DISPLAY 0.468085 (-6500 -2200);
PAINT GREEN (-6500 -2200);
DISPLAY INVISIBLE (-6500 -2200);
FORCEPROP 2 LAST PAGE_BORDER TRUE
J 0
(-14390 3050);
DISPLAY 0.638298 (-14390 3050);
PAINT PINK (-14390 3050);
DISPLAY INVISIBLE (-14390 3050);
FORCEPROP 1 LAST COMMENT_BODY TRUE
J 0
(-6488 -2213);
DISPLAY 0.978723 (-6488 -2213);
PAINT GREEN (-6488 -2213);
DISPLAY INVISIBLE (-6488 -2213);
WIRE 16 -1 (-11875 525)(-11875 475);
WIRE 16 -1 (-14125 -325)(-14125 -400);
WIRE 16 -1 (-10850 2400)(-10850 2350);
WIRE 16 -1 (-10825 3975)(-10825 3925);
WIRE 16 -1 (-10125 2475)(-10125 2275);
WIRE 16 -1 (-10100 3950)(-10100 3850);
WIRE 16 -1 (-8325 2350)(-8325 2250);
WIRE 16 -1 (-8400 3925)(-8400 3825);
WIRE 16 -1 (-7825 525)(-7825 475);
WIRE 16 -1 (-7925 3925)(-7925 3825);
WIRE 16 -1 (-11725 200)(-11725 150);
WIRE 16 -1 (-13000 -500)(-13000 -625);
WIRE 16 -1 (-13000 -500)(-12875 -500);
WIRE 16 -1 (-14075 -1075)(-14075 -1175);
WIRE 16 -1 (-8950 -500)(-8950 -625);
WIRE 16 -1 (-8950 -500)(-8825 -500);
WIRE 16 -1 (-12650 1025)(-12650 1075);
WIRE 16 -1 (-11875 1225)(-11875 1275);
WIRE 16 -1 (-10700 2100)(-10700 2025);
WIRE 16 -1 (-11850 2800)(-11850 2850);
WIRE 16 -1 (-10675 3675)(-10675 3600);
WIRE 16 -1 (-9000 1700)(-9000 1725);
WIRE 16 -1 (-9000 3275)(-9000 3300);
WIRE 16 -1 (-7675 200)(-7675 150);
WIRE 16 -1 (-14775 -750)(-14125 -750);
WIRE 16 -1 (-14125 -600)(-14125 -750);
WIRE 16 -1 (-12875 -300)(-13175 -300);
WIRE 16 -1 (-13175 -300)(-13175 -400);
WIRE 16 -1 (-13175 -400)(-12875 -400);
WIRE 16 -1 (-14075 -750)(-14125 -750);
WIRE 16 -1 (-14075 -875)(-14075 -750);
WIRE 16 -1 (-13175 -750)(-14075 -750);
FORCEPROP 2 LAST SIG_NAME FM_JTAG_BMC_MUX_SEL
J 0
(-13910 -740);
DISPLAY 0.680851 (-13910 -740);
PAINT WHITE (-13910 -740);
WIRE 16 -1 (-13175 -400)(-13175 -750);
WIRE 16 -1 (-9125 -750)(-13175 -750);
WIRE 16 -1 (-9125 -400)(-9125 -750);
WIRE 16 -1 (-9125 -400)(-8825 -400);
WIRE 16 -1 (-9125 -300)(-9125 -400);
WIRE 16 -1 (-9125 -300)(-8825 -300);
WIRE 16 -1 (-12075 -400)(-11200 -400);
FORCEPROP 0 LAST CDS_PHYS_NET_NAME JTAG_BMC_PLD_TDO
J 0
(-11885 -358);
PAINT MONO (-11885 -358);
DISPLAY INVISIBLE (-11885 -358);
FORCEPROP 2 LAST SIG_NAME JTAG_BMC_PLD_TDO
J 0
(-11885 -390);
DISPLAY 0.680851 (-11885 -390);
PAINT WHITE (-11885 -390);
WIRE 16 -1 (-12075 0)(-11200 0);
FORCEPROP 0 LAST CDS_PHYS_NET_NAME JTAG_BMC_DBP_TDI
J 0
(-11885 42);
PAINT MONO (-11885 42);
DISPLAY INVISIBLE (-11885 42);
FORCEPROP 2 LAST SIG_NAME JTAG_BMC_DBP_TDI
J 0
(-11885 10);
DISPLAY 0.680851 (-11885 10);
PAINT WHITE (-11885 10);
WIRE 16 -1 (-12075 -100)(-11200 -100);
FORCEPROP 0 LAST CDS_PHYS_NET_NAME JTAG_BMC_DBP_TDO
J 0
(-11885 -58);
PAINT MONO (-11885 -58);
DISPLAY INVISIBLE (-11885 -58);
FORCEPROP 2 LAST SIG_NAME JTAG_BMC_DBP_TDO
J 0
(-11885 -90);
DISPLAY 0.680851 (-11885 -90);
PAINT WHITE (-11885 -90);
WIRE 16 -1 (-12075 -300)(-11200 -300);
FORCEPROP 0 LAST CDS_PHYS_NET_NAME JTAG_BMC_PLD_TDI
J 0
(-11885 -258);
PAINT MONO (-11885 -258);
DISPLAY INVISIBLE (-11885 -258);
FORCEPROP 2 LAST SIG_NAME JTAG_BMC_PLD_TDI
J 0
(-11885 -290);
DISPLAY 0.680851 (-11885 -290);
PAINT WHITE (-11885 -290);
WIRE 16 -1 (-8325 1900)(-8325 1625);
WIRE 16 -1 (-7800 1625)(-8325 1625);
WIRE 16 -1 (-9850 1625)(-8325 1625);
FORCEPROP 2 LAST SIG_NAME JTAG_BMC_DBP_TDO
J 0
(-8835 1635);
DISPLAY 0.553191 (-8835 1635);
PAINT WHITE (-8835 1635);
WIRE 16 -1 (-12100 -1400)(-12100 -1500);
WIRE 16 -1 (-12325 -1500)(-12100 -1500);
WIRE 16 -1 (-12325 -1400)(-12325 -1500);
WIRE 16 -1 (-12325 -1400)(-12100 -1400);
WIRE 16 -1 (-12100 -1500)(-11550 -1500);
WIRE 16 -1 (-11550 -1500)(-11000 -1500);
WIRE 16 -1 (-11000 -1400)(-12100 -1400);
WIRE 16 -1 (-11000 -1400)(-11000 -1500);
WIRE 16 -1 (-12100 -1300)(-12100 -1400);
WIRE 16 -1 (-12100 -1300)(-11000 -1300);
WIRE 16 -1 (-11000 -1300)(-11000 -1400);
WIRE 16 -1 (-11550 -1150)(-11550 -1500);
WIRE 16 -1 (-12100 -1150)(-12100 -1300);
WIRE 16 -1 (-11550 -1150)(-12100 -1150);
WIRE 16 -1 (-12325 -1300)(-12325 -1400);
WIRE 16 -1 (-12100 -1300)(-12325 -1300);
WIRE 16 -1 (-12325 -1150)(-12325 -1300);
WIRE 16 -1 (-12325 -1150)(-12100 -1150);
WIRE 16 -1 (-11000 -1150)(-11550 -1150);
WIRE 16 -1 (-11000 -1150)(-11000 -1300);
WIRE 16 -1 (-11000 -1150)(-11000 -1050);
WIRE 16 -1 (-12325 -1150)(-12325 -1050);
WIRE 16 -1 (-12325 -1050)(-11000 -1050);
WIRE 16 -1 (-11875 100)(-12075 100);
WIRE 16 -1 (-11875 475)(-11875 100);
WIRE 16 -1 (-11725 475)(-11875 475);
WIRE 16 -1 (-11725 400)(-11725 475);
WIRE 16 -1 (-12875 0)(-14050 0);
FORCEPROP 2 LAST SIG_NAME JTAG_BMC_SW_TDI
J 0
(-13910 10);
DISPLAY 0.680851 (-13910 10);
PAINT WHITE (-13910 10);
WIRE 16 -1 (-10150 -100)(-8825 -100);
FORCEPROP 2 LAST SIG_NAME JTAG_BMC_SW_TCK
J 0
(-10035 -90);
DISPLAY 0.680851 (-10035 -90);
PAINT WHITE (-10035 -90);
WIRE 16 -1 (-10150 0)(-8825 0);
FORCEPROP 2 LAST SIG_NAME JTAG_BMC_SW_TMS
J 0
(-10035 10);
DISPLAY 0.680851 (-10035 10);
PAINT WHITE (-10035 10);
WIRE 16 -1 (-14050 -100)(-12875 -100);
FORCEPROP 2 LAST SIG_NAME JTAG_BMC_SW_TDO
J 0
(-13910 -90);
DISPLAY 0.680851 (-13910 -90);
PAINT WHITE (-13910 -90);
WIRE 16 -1 (-10250 1475)(-10950 1475);
FORCEPROP 2 LAST SIG_NAME TP_JTAG_BMC_A0
J 0
(-10825 1485);
DISPLAY 0.553191 (-10825 1485);
PAINT WHITE (-10825 1485);
WIRE 16 -1 (-8025 -400)(-7150 -400);
FORCEPROP 0 LAST CDS_PHYS_NET_NAME JTAG_BMC_PLD_TCK
J 0
(-7835 -358);
PAINT MONO (-7835 -358);
DISPLAY INVISIBLE (-7835 -358);
FORCEPROP 2 LAST SIG_NAME JTAG_BMC_PLD_TCK
J 0
(-7835 -390);
DISPLAY 0.680851 (-7835 -390);
PAINT WHITE (-7835 -390);
WIRE 16 -1 (-8025 -300)(-7150 -300);
FORCEPROP 0 LAST CDS_PHYS_NET_NAME JTAG_BMC_PLD_TMS
J 0
(-7835 -258);
PAINT MONO (-7835 -258);
DISPLAY INVISIBLE (-7835 -258);
FORCEPROP 2 LAST SIG_NAME JTAG_BMC_PLD_TMS
J 0
(-7835 -290);
DISPLAY 0.680851 (-7835 -290);
PAINT WHITE (-7835 -290);
WIRE 16 -1 (-8025 -100)(-7150 -100);
FORCEPROP 0 LAST CDS_PHYS_NET_NAME JTAG_BMC_DBP_TCK
J 0
(-7835 -58);
PAINT MONO (-7835 -58);
DISPLAY INVISIBLE (-7835 -58);
FORCEPROP 2 LAST SIG_NAME JTAG_BMC_DBP_TCK
J 0
(-7835 -90);
DISPLAY 0.680851 (-7835 -90);
PAINT WHITE (-7835 -90);
WIRE 16 -1 (-8025 0)(-7150 0);
FORCEPROP 0 LAST CDS_PHYS_NET_NAME JTAG_BMC_DBP_TMS
J 0
(-7835 42);
PAINT MONO (-7835 42);
DISPLAY INVISIBLE (-7835 42);
FORCEPROP 2 LAST SIG_NAME JTAG_BMC_DBP_TMS
J 0
(-7835 10);
DISPLAY 0.680851 (-7835 10);
PAINT WHITE (-7835 10);
WIRE 16 -1 (-13175 1525)(-14050 1525);
FORCEPROP 2 LAST SIG_NAME JTAG_DBP_PRDY_N
J 0
(-13835 1535);
DISPLAY 0.553191 (-13835 1535);
PAINT WHITE (-13835 1535);
WIRE 16 -1 (-13175 1625)(-14050 1625);
FORCEPROP 2 LAST SIG_NAME JTAG_DBP_TDO
J 0
(-13835 1635);
DISPLAY 0.553191 (-13835 1635);
PAINT WHITE (-13835 1635);
WIRE 16 -1 (-11750 1525)(-12975 1525);
FORCEPROP 2 LAST SIG_NAME JTAG_DBP_PRDY_R_N
J 0
(-12335 1535);
DISPLAY 0.553191 (-12335 1535);
PAINT WHITE (-12335 1535);
WIRE 16 -1 (-11750 1625)(-12975 1625);
FORCEPROP 2 LAST SIG_NAME JTAG_DBP_FB_TDO
J 0
(-12335 1635);
DISPLAY 0.553191 (-12335 1635);
PAINT WHITE (-12335 1635);
WIRE 16 -1 (-13150 3050)(-14025 3050);
FORCEPROP 2 LAST SIG_NAME JTAG_DBP_PREQ_N
J 0
(-13810 3060);
DISPLAY 0.553191 (-13810 3060);
PAINT WHITE (-13810 3060);
WIRE 16 -1 (-14025 3100)(-11725 3100);
FORCEPROP 2 LAST SIG_NAME FM_CPU_FBRK_DEBUG_N
J 0
(-12585 3110);
DISPLAY 0.553191 (-12585 3110);
PAINT WHITE (-12585 3110);
WIRE 16 -1 (-13150 3150)(-14025 3150);
FORCEPROP 2 LAST SIG_NAME JTAG_DBP_TDI
J 0
(-13810 3160);
DISPLAY 0.553191 (-13810 3160);
PAINT WHITE (-13810 3160);
WIRE 16 -1 (-13150 3200)(-14025 3200);
FORCEPROP 2 LAST SIG_NAME JTAG_DBP_TMS
J 0
(-13810 3210);
DISPLAY 0.553191 (-13810 3210);
PAINT WHITE (-13810 3210);
WIRE 16 -1 (-11725 3050)(-12950 3050);
FORCEPROP 2 LAST SIG_NAME JTAG_DBP_PREQ_R_N
J 0
(-12585 3060);
DISPLAY 0.553191 (-12585 3060);
PAINT WHITE (-12585 3060);
WIRE 16 -1 (-11725 3150)(-12950 3150);
FORCEPROP 2 LAST SIG_NAME JTAG_DBP_FB_TDI
J 0
(-12585 3160);
DISPLAY 0.553191 (-12585 3160);
PAINT WHITE (-12585 3160);
WIRE 16 -1 (-11725 3200)(-12950 3200);
FORCEPROP 2 LAST SIG_NAME JTAG_DBP_FB_TMS
J 0
(-12585 3210);
DISPLAY 0.553191 (-12585 3210);
PAINT WHITE (-12585 3210);
WIRE 16 -1 (-9550 1725)(-10950 1725);
FORCEPROP 2 LAST SIG_NAME PD_GTL2014_BMC_JTAG_DIR_2
J 0
(-10825 1735);
DISPLAY 0.446809 (-10825 1735);
PAINT WHITE (-10825 1735);
WIRE 16 -1 (-10050 1525)(-10950 1525);
FORCEPROP 2 LAST SIG_NAME JTAG_DBP_BMC_PRDY_R1_N
J 0
(-10825 1535);
DISPLAY 0.553191 (-10825 1535);
PAINT WHITE (-10825 1535);
WIRE 16 -1 (-10250 1575)(-10950 1575);
FORCEPROP 2 LAST SIG_NAME TP_JTAG_BMC_A2
J 0
(-10825 1585);
DISPLAY 0.553191 (-10825 1585);
PAINT WHITE (-10825 1585);
WIRE 16 -1 (-10050 1625)(-10950 1625);
FORCEPROP 2 LAST SIG_NAME JTAG_BMC_DBP_TDO_R
J 0
(-10825 1635);
DISPLAY 0.553191 (-10825 1635);
PAINT WHITE (-10825 1635);
WIRE 16 -1 (-11750 1575)(-12650 1575);
FORCEPROP 2 LAST SIG_NAME PD_JTAG_DBP_B2
J 0
(-12335 1585);
DISPLAY 0.553191 (-12335 1585);
PAINT WHITE (-12335 1585);
WIRE 16 -1 (-12650 1350)(-12650 1575);
WIRE 16 -1 (-11750 1475)(-12425 1475);
FORCEPROP 2 LAST SIG_NAME PD_JTAG_DBP_B0
J 0
(-12335 1485);
DISPLAY 0.553191 (-12335 1485);
PAINT WHITE (-12335 1485);
WIRE 16 -1 (-12425 1350)(-12425 1475);
WIRE 16 -1 (-10925 3400)(-9500 3400);
FORCEPROP 2 LAST SIG_NAME PD_GTL2014_BMC_JTAG_VREF_1
J 0
(-10750 3410);
DISPLAY 0.446809 (-10750 3410);
PAINT WHITE (-10750 3410);
WIRE 16 -1 (-10925 3050)(-9950 3050);
FORCEPROP 2 LAST SIG_NAME JTAG_DBP_BMC_PREQ_R1_N
J 0
(-10750 3060);
DISPLAY 0.446809 (-10750 3060);
PAINT WHITE (-10750 3060);
WIRE 16 -1 (-9950 3150)(-10925 3150);
FORCEPROP 2 LAST SIG_NAME JTAG_BMC_DBP_TDI_R
J 0
(-10750 3160);
DISPLAY 0.446809 (-10750 3160);
PAINT WHITE (-10750 3160);
WIRE 16 -1 (-9950 3200)(-10925 3200);
FORCEPROP 2 LAST SIG_NAME JTAG_BMC_DBP_TMS_R
J 0
(-10750 3210);
DISPLAY 0.446809 (-10750 3210);
PAINT WHITE (-10750 3210);
WIRE 16 -1 (-7625 1400)(-8550 1400);
FORCEPROP 2 LAST SIG_NAME JTAG_DBP_BMC_PRDY_R_N
J 0
(-8200 1410);
DISPLAY 0.446809 (-8200 1410);
PAINT WHITE (-8200 1410);
WIRE 16 -1 (-10100 3650)(-10100 3300);
WIRE 16 -1 (-9500 3300)(-10100 3300);
WIRE 16 -1 (-10925 3300)(-10100 3300);
FORCEPROP 2 LAST SIG_NAME PU_GTL2014_BMC_JTAG_DIR_1
J 0
(-10750 3310);
DISPLAY 0.446809 (-10750 3310);
PAINT WHITE (-10750 3310);
WIRE 16 -1 (-7600 2925)(-8525 2925);
FORCEPROP 2 LAST SIG_NAME JTAG_DBP_BMC_PREQ_R_N
J 0
(-8175 2935);
DISPLAY 0.446809 (-8175 2935);
PAINT WHITE (-8175 2935);
WIRE 16 -1 (-8175 3150)(-9750 3150);
FORCEPROP 2 LAST SIG_NAME JTAG_BMC_DBP_TDI
J 0
(-8835 3160);
DISPLAY 0.446809 (-8835 3160);
PAINT WHITE (-8835 3160);
WIRE 16 -1 (-8175 3475)(-8175 3150);
WIRE 16 -1 (-7600 3150)(-8175 3150);
WIRE 16 -1 (-7925 3475)(-7925 3100);
WIRE 16 -1 (-7600 3100)(-7925 3100);
WIRE 16 -1 (-10925 3100)(-7925 3100);
FORCEPROP 2 LAST SIG_NAME FM_BMC_CPU_FBRK_OUT_N
J 0
(-10750 3110);
DISPLAY 0.446809 (-10750 3110);
PAINT WHITE (-10750 3110);
WIRE 16 -1 (-8400 3200)(-9750 3200);
FORCEPROP 2 LAST SIG_NAME JTAG_BMC_DBP_TMS
J 0
(-8835 3210);
DISPLAY 0.446809 (-8835 3210);
PAINT WHITE (-8835 3210);
WIRE 16 -1 (-8400 3475)(-8400 3200);
WIRE 16 -1 (-7600 3200)(-8400 3200);
WIRE 16 -1 (-12650 1075)(-12650 1150);
WIRE 16 -1 (-12425 1075)(-12650 1075);
WIRE 16 -1 (-12425 1150)(-12425 1075);
WIRE 16 -1 (-11875 1375)(-11750 1375);
WIRE 16 -1 (-11875 1375)(-11875 1325);
WIRE 16 -1 (-11875 1325)(-11750 1325);
WIRE 16 -1 (-11875 1325)(-11875 1275);
WIRE 16 -1 (-11750 1275)(-11875 1275);
WIRE 16 -1 (-11725 2850)(-11850 2850);
WIRE 16 -1 (-11850 2900)(-11850 2850);
WIRE 16 -1 (-11850 2900)(-11725 2900);
WIRE 16 -1 (-11850 2950)(-11850 2900);
WIRE 16 -1 (-11850 2950)(-11725 2950);
WIRE 16 -1 (-10950 1875)(-10850 1875);
WIRE 16 -1 (-10850 1875)(-10850 2350);
WIRE 16 -1 (-10850 2350)(-10700 2350);
WIRE 16 -1 (-10700 2300)(-10700 2350);
WIRE 16 -1 (-10925 3450)(-10825 3450);
WIRE 16 -1 (-10825 3450)(-10825 3925);
WIRE 16 -1 (-10825 3925)(-10675 3925);
WIRE 16 -1 (-10675 3875)(-10675 3925);
WIRE 16 -1 (-9550 2075)(-9750 2075);
WIRE 16 -1 (-9750 1825)(-9550 1825);
WIRE 16 -1 (-9750 2075)(-9750 1825);
WIRE 16 -1 (-10125 1825)(-9750 1825);
WIRE 16 -1 (-10125 2075)(-10125 1825);
WIRE 16 -1 (-10950 1825)(-10125 1825);
FORCEPROP 2 LAST SIG_NAME P0V7_JTAG_VREF_2
J 0
(-10825 1835);
DISPLAY 0.446809 (-10825 1835);
PAINT WHITE (-10825 1835);
WIRE 16 -1 (-9000 1400)(-8750 1400);
WIRE 16 -1 (-9000 1525)(-9850 1525);
WIRE 16 -1 (-9000 1525)(-9000 1400);
WIRE 16 -1 (-8100 1525)(-9000 1525);
FORCEPROP 2 LAST SIG_NAME JTAG_DBP_BMC_PRDY_N
J 0
(-8560 1535);
DISPLAY 0.553191 (-8560 1535);
PAINT WHITE (-8560 1535);
WIRE 16 -1 (-8100 1900)(-8100 1525);
WIRE 16 -1 (-7800 1525)(-8100 1525);
WIRE 16 -1 (-9000 2075)(-9350 2075);
WIRE 16 -1 (-9000 1825)(-9350 1825);
WIRE 16 -1 (-9000 1825)(-9000 2075);
WIRE 16 -1 (-9000 1725)(-9000 1825);
WIRE 16 -1 (-9350 1725)(-9000 1725);
WIRE 16 -1 (-9000 2925)(-8725 2925);
WIRE 16 -1 (-9750 3050)(-9000 3050);
WIRE 16 -1 (-9000 3050)(-9000 2925);
WIRE 16 -1 (-9000 3050)(-7700 3050);
FORCEPROP 2 LAST SIG_NAME JTAG_BMC_DBP_PREQ_N
J 0
(-8835 3060);
DISPLAY 0.446809 (-8835 3060);
PAINT WHITE (-8835 3060);
WIRE 16 -1 (-7700 3475)(-7700 3050);
WIRE 16 -1 (-7600 3050)(-7700 3050);
WIRE 16 -1 (-8100 2250)(-8100 2100);
WIRE 16 -1 (-8100 2250)(-8325 2250);
WIRE 16 -1 (-8325 2100)(-8325 2250);
WIRE 16 -1 (-9000 3400)(-9300 3400);
WIRE 16 -1 (-9300 3300)(-9000 3300);
WIRE 16 -1 (-9000 3300)(-9000 3400);
WIRE 16 -1 (-8175 3825)(-8175 3675);
WIRE 16 -1 (-8175 3825)(-8400 3825);
WIRE 16 -1 (-8400 3675)(-8400 3825);
WIRE 16 -1 (-7825 100)(-8025 100);
WIRE 16 -1 (-7825 475)(-7825 100);
WIRE 16 -1 (-7675 475)(-7825 475);
WIRE 16 -1 (-7675 400)(-7675 475);
WIRE 16 -1 (-7700 3825)(-7700 3675);
WIRE 16 -1 (-7700 3825)(-7925 3825);
WIRE 16 -1 (-7925 3675)(-7925 3825);
DOT 1 (-11875 475);
DOT 1 (-14125 -750);
DOT 1 (-14075 -750);
DOT 1 (-12325 -1400);
DOT 1 (-12325 -1300);
DOT 1 (-12325 -1150);
DOT 1 (-13175 -750);
DOT 1 (-13175 -400);
DOT 1 (-12100 -1500);
DOT 1 (-12100 -1400);
DOT 1 (-12100 -1300);
DOT 1 (-12100 -1150);
DOT 1 (-11550 -1500);
DOT 1 (-11550 -1150);
DOT 1 (-11000 -1400);
DOT 1 (-11000 -1300);
DOT 1 (-11000 -1150);
DOT 1 (-9125 -400);
DOT 1 (-12650 1075);
DOT 1 (-11875 1275);
DOT 1 (-11875 1325);
DOT 1 (-11850 2850);
DOT 1 (-11850 2900);
DOT 1 (-10850 2350);
DOT 1 (-10825 3925);
DOT 1 (-10125 1825);
DOT 1 (-9750 1825);
DOT 1 (-9000 1525);
DOT 1 (-9000 1725);
DOT 1 (-9000 1825);
DOT 1 (-8100 1525);
DOT 1 (-8325 1625);
DOT 1 (-10100 3300);
DOT 1 (-9000 3050);
DOT 1 (-8325 2250);
DOT 1 (-8175 3150);
DOT 1 (-9000 3300);
DOT 1 (-8400 3200);
DOT 1 (-8400 3825);
DOT 1 (-7825 475);
DOT 1 (-7925 3100);
DOT 1 (-7700 3050);
DOT 1 (-7925 3825);
FORCENOTE
20210607 MODIFY FOR GT
(-11200 625) 0;
DISPLAY LEFT (-11200 625);
DISPLAY 1.595745 (-11200 625);
PAINT PINK (-11200 625);
FORCENOTE
FUNCTION TABLE
(-12000 -1125) 0;
DISPLAY LEFT (-12000 -1125);
DISPLAY 1.021277 (-12000 -1125);
PAINT WHITE (-12000 -1125);
FORCENOTE
L
(-12225 -1375) 0;
DISPLAY LEFT (-12225 -1375);
DISPLAY 1.021277 (-12225 -1375);
PAINT WHITE (-12225 -1375);
FORCENOTE
IN
(-12250 -1250) 0;
DISPLAY LEFT (-12250 -1250);
DISPLAY 1.021277 (-12250 -1250);
PAINT WHITE (-12250 -1250);
FORCENOTE
H
(-12225 -1475) 0;
DISPLAY LEFT (-12225 -1475);
DISPLAY 1.021277 (-12225 -1475);
PAINT WHITE (-12225 -1475);
FORCENOTE
OFF
(-11900 -1475) 0;
DISPLAY LEFT (-11900 -1475);
DISPLAY 1.021277 (-11900 -1475);
PAINT WHITE (-11900 -1475);
FORCENOTE
ON
(-11875 -1375) 0;
DISPLAY LEFT (-11875 -1375);
DISPLAY 1.021277 (-11875 -1375);
PAINT WHITE (-11875 -1375);
FORCENOTE
NC TO COM,
(-12050 -1225) 0;
DISPLAY LEFT (-12050 -1225);
DISPLAY 1.021277 (-12050 -1225);
PAINT WHITE (-12050 -1225);
FORCENOTE
COM TO NC
(-12050 -1275) 0;
DISPLAY LEFT (-12050 -1275);
DISPLAY 1.021277 (-12050 -1275);
PAINT WHITE (-12050 -1275);
FORCENOTE
ON
(-11325 -1475) 0;
DISPLAY LEFT (-11325 -1475);
DISPLAY 1.021277 (-11325 -1475);
PAINT WHITE (-11325 -1475);
FORCENOTE
OFF
(-11350 -1375) 0;
DISPLAY LEFT (-11350 -1375);
DISPLAY 1.021277 (-11350 -1375);
PAINT WHITE (-11350 -1375);
FORCENOTE
COM TO NO
(-11500 -1275) 0;
DISPLAY LEFT (-11500 -1275);
DISPLAY 1.021277 (-11500 -1275);
PAINT WHITE (-11500 -1275);
FORCENOTE
NO TO COM,
(-11500 -1225) 0;
DISPLAY LEFT (-11500 -1225);
DISPLAY 1.021277 (-11500 -1225);
PAINT WHITE (-11500 -1225);
QUIT
